(kicad_sch
	(version 20250114)
	(generator "eeschema")
	(generator_version "9.0")
	(paper "A3")
	(title_block
		(title "RDIMM DDR5 Tester")
		(date "2026-05-21")
		(rev "2.2.0")
		(company "Antmicro")
		(comment 1 "www.antmicro.com")
		(comment 2 "Antmicro")
	)
	(text "BANK 64\n"
		(exclude_from_sim no)
		(at 163.83 224.79 0)
		(effects
			(font
				(size 1.27 1.27)
			)
			(justify left bottom)
		)
	)
	(text "VCCBAT : 1.8V"
		(exclude_from_sim no)
		(at 168.91 133.35 0)
		(effects
			(font
				(size 1.27 1.27)
			)
			(justify right bottom)
		)
	)
	(text "FPGA Power rails"
		(exclude_from_sim no)
		(at 13.335 18.415 0)
		(effects
			(font
				(size 3 3)
				(thickness 0.6)
				(bold yes)
			)
			(justify left bottom)
		)
	)
	(text "BANK 84"
		(exclude_from_sim no)
		(at 203.2 255.27 0)
		(effects
			(font
				(size 1.27 1.27)
			)
			(justify left bottom)
		)
	)
	(text "BANK 65\n"
		(exclude_from_sim no)
		(at 194.31 224.79 0)
		(effects
			(font
				(size 1.27 1.27)
			)
			(justify left bottom)
		)
	)
	(text "VCCADC : 1.8V"
		(exclude_from_sim no)
		(at 168.91 130.81 0)
		(effects
			(font
				(size 1.27 1.27)
			)
			(justify right bottom)
		)
	)
	(text "V_{CCAUX}"
		(exclude_from_sim no)
		(at 40.64 230.505 0)
		(effects
			(font
				(size 1.27 1.27)
			)
			(justify left bottom)
		)
	)
	(text "BANK 0"
		(exclude_from_sim no)
		(at 166.37 255.27 0)
		(effects
			(font
				(size 1.27 1.27)
			)
			(justify left bottom)
		)
	)
	(text "Bank decoupling"
		(exclude_from_sim no)
		(at 142.24 219.71 0)
		(effects
			(font
				(size 2 2)
				(thickness 0.6)
				(bold yes)
			)
			(justify left bottom)
		)
	)
	(text "Trace length from the resistor pins to the\nFPGA pins MGTRREF and MGTAVTTRCAL\nmust be equal in length."
		(exclude_from_sim no)
		(at 220.98 128.905 0)
		(effects
			(font
				(size 1 1)
			)
			(justify left bottom)
		)
	)
	(text "FPGA"
		(exclude_from_sim no)
		(at 143.51 17.78 0)
		(effects
			(font
				(size 2 2)
				(thickness 0.6)
				(bold yes)
			)
			(justify left bottom)
		)
	)
	(text "VCCINT_IO: 0.85V"
		(exclude_from_sim no)
		(at 168.91 120.65 0)
		(effects
			(font
				(size 1.27 1.27)
			)
			(justify right bottom)
		)
	)
	(text "VCCINT decoupling"
		(exclude_from_sim no)
		(at 16.51 220.98 0)
		(effects
			(font
				(size 2 2)
				(thickness 0.6)
				(bold yes)
			)
			(justify left bottom)
		)
	)
	(text "VTTRCAL : 1.2V"
		(exclude_from_sim no)
		(at 259.08 138.43 0)
		(effects
			(font
				(size 1.27 1.27)
			)
			(justify left bottom)
		)
	)
	(text "VCCAVCC : 0.9V"
		(exclude_from_sim no)
		(at 259.08 133.35 0)
		(effects
			(font
				(size 1.27 1.27)
			)
			(justify left bottom)
		)
	)
	(text "MGTVCCAUX : 1.8V"
		(exclude_from_sim no)
		(at 259.08 135.89 0)
		(effects
			(font
				(size 1.27 1.27)
			)
			(justify left bottom)
		)
	)
	(text "BANK 87"
		(exclude_from_sim no)
		(at 269.24 255.27 0)
		(effects
			(font
				(size 1.27 1.27)
			)
			(justify left bottom)
		)
	)
	(text "VCCBRAM : 0.85V"
		(exclude_from_sim no)
		(at 168.91 128.27 0)
		(effects
			(font
				(size 1.27 1.27)
			)
			(justify right bottom)
		)
	)
	(text "VCCAVTT : 1.2V"
		(exclude_from_sim no)
		(at 259.08 130.81 0)
		(effects
			(font
				(size 1.27 1.27)
			)
			(justify left bottom)
		)
	)
	(text "BANK 67\n"
		(exclude_from_sim no)
		(at 262.89 224.79 0)
		(effects
			(font
				(size 1.27 1.27)
			)
			(justify left bottom)
		)
	)
	(text "V_{CCINT}"
		(exclude_from_sim no)
		(at 59.055 56.515 0)
		(effects
			(font
				(size 1.27 1.27)
			)
			(justify left bottom)
		)
	)
	(text "MGT decoupling"
		(exclude_from_sim no)
		(at 302.26 19.05 0)
		(effects
			(font
				(size 2 2)
				(thickness 0.6)
				(bold yes)
			)
			(justify left bottom)
		)
	)
	(text "VCCINT : 0.85V"
		(exclude_from_sim no)
		(at 168.91 118.11 0)
		(effects
			(font
				(size 1.27 1.27)
			)
			(justify right bottom)
		)
	)
	(text "Bank marked by dashed line \nreferenced from US+ Series FPGAs\nPCB Design Guide UG583\n(AUP25P+ XCKU5P FFVB Package worst case)"
		(exclude_from_sim no)
		(at 13.97 27.305 0)
		(effects
			(font
				(size 1.27 1.27)
			)
			(justify left bottom)
		)
	)
	(text "V_{CCBRAM}"
		(exclude_from_sim no)
		(at 41.275 83.185 0)
		(effects
			(font
				(size 1.27 1.27)
			)
			(justify left bottom)
		)
	)
	(text "VCCAUX_IO : 1.8V"
		(exclude_from_sim no)
		(at 168.91 125.73 0)
		(effects
			(font
				(size 1.27 1.27)
			)
			(justify right bottom)
		)
	)
	(text "BANK 86"
		(exclude_from_sim no)
		(at 236.22 255.27 0)
		(effects
			(font
				(size 1.27 1.27)
			)
			(justify left bottom)
		)
	)
	(text "MGT decoupling marked by dahed line \nreferenced from US+ Series FPGAs\nPCB Design Guide UG576 \n(AUP25P+ XCKU5P FFVB Package worst case)"
		(exclude_from_sim no)
		(at 13.97 36.195 0)
		(effects
			(font
				(size 1.27 1.27)
			)
			(justify left bottom)
		)
	)
	(text "VCCAUX : 1.8V"
		(exclude_from_sim no)
		(at 168.91 123.19 0)
		(effects
			(font
				(size 1.27 1.27)
			)
			(justify right bottom)
		)
	)
	(text "VCCINT decoupling"
		(exclude_from_sim no)
		(at 13.97 44.45 0)
		(effects
			(font
				(size 2 2)
				(thickness 0.6)
				(bold yes)
			)
			(justify left bottom)
		)
	)
	(text "BANK 66\n"
		(exclude_from_sim no)
		(at 224.79 224.79 0)
		(effects
			(font
				(size 1.27 1.27)
			)
			(justify left bottom)
		)
	)
	(junction
		(at 365.76 127)
		(diameter 0)
		(color 0 0 0 0)
	)
	(junction
		(at 44.45 138.43)
		(diameter 0)
		(color 0 0 0 0)
	)
	(junction
		(at 332.74 93.98)
		(diameter 0)
		(color 0 0 0 0)
	)
	(junction
		(at 356.87 127)
		(diameter 0)
		(color 0 0 0 0)
	)
	(junction
		(at 269.24 114.3)
		(diameter 0)
		(color 0 0 0 0)
	)
	(junction
		(at 191.77 232.41)
		(diameter 0)
		(color 0 0 0 0)
	)
	(junction
		(at 232.41 232.41)
		(diameter 0)
		(color 0 0 0 0)
	)
	(junction
		(at 44.45 163.83)
		(diameter 0)
		(color 0 0 0 0)
	)
	(junction
		(at 53.34 163.83)
		(diameter 0)
		(color 0 0 0 0)
	)
	(junction
		(at 69.85 138.43)
		(diameter 0)
		(color 0 0 0 0)
	)
	(junction
		(at 256.54 231.14)
		(diameter 0)
		(color 0 0 0 0)
	)
	(junction
		(at 87.63 187.96)
		(diameter 0)
		(color 0 0 0 0)
	)
	(junction
		(at 104.14 187.96)
		(diameter 0)
		(color 0 0 0 0)
	)
	(junction
		(at 340.36 127)
		(diameter 0)
		(color 0 0 0 0)
	)
	(junction
		(at 78.74 187.96)
		(diameter 0)
		(color 0 0 0 0)
	)
	(junction
		(at 62.23 187.96)
		(diameter 0)
		(color 0 0 0 0)
	)
	(junction
		(at 240.03 262.89)
		(diameter 0)
		(color 0 0 0 0)
	)
	(junction
		(at 53.34 138.43)
		(diameter 0)
		(color 0 0 0 0)
	)
	(junction
		(at 354.33 58.42)
		(diameter 0)
		(color 0 0 0 0)
	)
	(junction
		(at 45.72 110.49)
		(diameter 0)
		(color 0 0 0 0)
	)
	(junction
		(at 40.64 232.41)
		(diameter 0)
		(color 0 0 0 0)
	)
	(junction
		(at 86.36 163.83)
		(diameter 0)
		(color 0 0 0 0)
	)
	(junction
		(at 226.06 134.62)
		(diameter 0)
		(color 0 0 0 0)
	)
	(junction
		(at 102.87 163.83)
		(diameter 0)
		(color 0 0 0 0)
	)
	(junction
		(at 36.83 86.36)
		(diameter 0)
		(color 0 0 0 0)
	)
	(junction
		(at 36.83 110.49)
		(diameter 0)
		(color 0 0 0 0)
	)
	(junction
		(at 163.83 232.41)
		(diameter 0)
		(color 0 0 0 0)
	)
	(junction
		(at 95.25 187.96)
		(diameter 0)
		(color 0 0 0 0)
	)
	(junction
		(at 226.06 137.16)
		(diameter 0)
		(color 0 0 0 0)
	)
	(junction
		(at 36.83 138.43)
		(diameter 0)
		(color 0 0 0 0)
	)
	(junction
		(at 340.36 93.98)
		(diameter 0)
		(color 0 0 0 0)
	)
	(junction
		(at 354.33 93.98)
		(diameter 0)
		(color 0 0 0 0)
	)
	(junction
		(at 36.83 163.83)
		(diameter 0)
		(color 0 0 0 0)
	)
	(junction
		(at 34.29 232.41)
		(diameter 0)
		(color 0 0 0 0)
	)
	(junction
		(at 69.85 163.83)
		(diameter 0)
		(color 0 0 0 0)
	)
	(junction
		(at 102.87 138.43)
		(diameter 0)
		(color 0 0 0 0)
	)
	(junction
		(at 69.85 187.96)
		(diameter 0)
		(color 0 0 0 0)
	)
	(junction
		(at 198.12 232.41)
		(diameter 0)
		(color 0 0 0 0)
	)
	(junction
		(at 262.89 231.14)
		(diameter 0)
		(color 0 0 0 0)
	)
	(junction
		(at 88.9 59.69)
		(diameter 0)
		(color 0 0 0 0)
	)
	(junction
		(at 71.12 59.69)
		(diameter 0)
		(color 0 0 0 0)
	)
	(junction
		(at 78.74 138.43)
		(diameter 0)
		(color 0 0 0 0)
	)
	(junction
		(at 60.96 163.83)
		(diameter 0)
		(color 0 0 0 0)
	)
	(junction
		(at 173.99 132.08)
		(diameter 0)
		(color 0 0 0 0)
	)
	(junction
		(at 361.95 93.98)
		(diameter 0)
		(color 0 0 0 0)
	)
	(junction
		(at 325.12 93.98)
		(diameter 0)
		(color 0 0 0 0)
	)
	(junction
		(at 38.1 59.69)
		(diameter 0)
		(color 0 0 0 0)
	)
	(junction
		(at 60.96 138.43)
		(diameter 0)
		(color 0 0 0 0)
	)
	(junction
		(at 349.25 127)
		(diameter 0)
		(color 0 0 0 0)
	)
	(junction
		(at 104.14 110.49)
		(diameter 0)
		(color 0 0 0 0)
	)
	(junction
		(at 345.44 166.37)
		(diameter 0)
		(color 0 0 0 0)
	)
	(junction
		(at 269.24 262.89)
		(diameter 0)
		(color 0 0 0 0)
	)
	(junction
		(at 99.06 59.69)
		(diameter 0)
		(color 0 0 0 0)
	)
	(junction
		(at 346.71 93.98)
		(diameter 0)
		(color 0 0 0 0)
	)
	(junction
		(at 50.8 232.41)
		(diameter 0)
		(color 0 0 0 0)
	)
	(junction
		(at 49.53 59.69)
		(diameter 0)
		(color 0 0 0 0)
	)
	(junction
		(at 60.96 59.69)
		(diameter 0)
		(color 0 0 0 0)
	)
	(junction
		(at 173.99 119.38)
		(diameter 0)
		(color 0 0 0 0)
	)
	(junction
		(at 27.94 59.69)
		(diameter 0)
		(color 0 0 0 0)
	)
	(junction
		(at 95.25 163.83)
		(diameter 0)
		(color 0 0 0 0)
	)
	(junction
		(at 107.95 59.69)
		(diameter 0)
		(color 0 0 0 0)
	)
	(junction
		(at 95.25 138.43)
		(diameter 0)
		(color 0 0 0 0)
	)
	(junction
		(at 204.47 264.16)
		(diameter 0)
		(color 0 0 0 0)
	)
	(junction
		(at 86.36 138.43)
		(diameter 0)
		(color 0 0 0 0)
	)
	(junction
		(at 270.51 231.14)
		(diameter 0)
		(color 0 0 0 0)
	)
	(junction
		(at 29.21 232.41)
		(diameter 0)
		(color 0 0 0 0)
	)
	(junction
		(at 80.01 59.69)
		(diameter 0)
		(color 0 0 0 0)
	)
	(junction
		(at 346.71 58.42)
		(diameter 0)
		(color 0 0 0 0)
	)
	(junction
		(at 69.85 110.49)
		(diameter 0)
		(color 0 0 0 0)
	)
	(junction
		(at 78.74 163.83)
		(diameter 0)
		(color 0 0 0 0)
	)
	(junction
		(at 53.34 187.96)
		(diameter 0)
		(color 0 0 0 0)
	)
	(junction
		(at 87.63 110.49)
		(diameter 0)
		(color 0 0 0 0)
	)
	(junction
		(at 274.32 121.92)
		(diameter 0)
		(color 0 0 0 0)
	)
	(junction
		(at 118.11 59.69)
		(diameter 0)
		(color 0 0 0 0)
	)
	(junction
		(at 58.42 232.41)
		(diameter 0)
		(color 0 0 0 0)
	)
	(junction
		(at 328.93 58.42)
		(diameter 0)
		(color 0 0 0 0)
	)
	(junction
		(at 62.23 110.49)
		(diameter 0)
		(color 0 0 0 0)
	)
	(junction
		(at 339.09 58.42)
		(diameter 0)
		(color 0 0 0 0)
	)
	(junction
		(at 173.99 121.92)
		(diameter 0)
		(color 0 0 0 0)
	)
	(junction
		(at 224.79 232.41)
		(diameter 0)
		(color 0 0 0 0)
	)
	(junction
		(at 95.25 110.49)
		(diameter 0)
		(color 0 0 0 0)
	)
	(junction
		(at 181.61 111.76)
		(diameter 0)
		(color 0 0 0 0)
	)
	(junction
		(at 171.45 232.41)
		(diameter 0)
		(color 0 0 0 0)
	)
	(junction
		(at 173.99 262.89)
		(diameter 0)
		(color 0 0 0 0)
	)
	(junction
		(at 181.61 114.3)
		(diameter 0)
		(color 0 0 0 0)
	)
	(junction
		(at 368.3 58.42)
		(diameter 0)
		(color 0 0 0 0)
	)
	(junction
		(at 160.02 262.89)
		(diameter 0)
		(color 0 0 0 0)
	)
	(junction
		(at 78.74 110.49)
		(diameter 0)
		(color 0 0 0 0)
	)
	(junction
		(at 330.2 127)
		(diameter 0)
		(color 0 0 0 0)
	)
	(junction
		(at 167.64 262.89)
		(diameter 0)
		(color 0 0 0 0)
	)
	(junction
		(at 361.95 58.42)
		(diameter 0)
		(color 0 0 0 0)
	)
	(junction
		(at 53.34 110.49)
		(diameter 0)
		(color 0 0 0 0)
	)
	(wire
		(pts
			(xy 44.45 163.83) (xy 53.34 163.83)
		)
		(stroke
			(width 0)
			(type default)
		)
	)
	(wire
		(pts
			(xy 354.33 58.42) (xy 361.95 58.42)
		)
		(stroke
			(width 0)
			(type default)
		)
	)
	(wire
		(pts
			(xy 69.85 163.83) (xy 78.74 163.83)
		)
		(stroke
			(width 0)
			(type default)
		)
	)
	(wire
		(pts
			(xy 345.44 175.26) (xy 345.44 173.99)
		)
		(stroke
			(width 0)
			(type default)
		)
	)
	(wire
		(pts
			(xy 198.12 232.41) (xy 205.74 232.41)
		)
		(stroke
			(width 0)
			(type default)
		)
	)
	(polyline
		(pts
			(xy 52.07 83.82) (xy 52.07 93.98)
		)
		(stroke
			(width 0)
			(type dash)
		)
	)
	(wire
		(pts
			(xy 86.36 167.64) (xy 86.36 163.83)
		)
		(stroke
			(width 0)
			(type default)
		)
	)
	(wire
		(pts
			(xy 53.34 114.3) (xy 53.34 110.49)
		)
		(stroke
			(width 0)
			(type default)
		)
	)
	(wire
		(pts
			(xy 86.36 163.83) (xy 95.25 163.83)
		)
		(stroke
			(width 0)
			(type default)
		)
	)
	(wire
		(pts
			(xy 111.76 167.64) (xy 111.76 163.83)
		)
		(stroke
			(width 0)
			(type default)
		)
	)
	(wire
		(pts
			(xy 173.99 132.08) (xy 182.88 132.08)
		)
		(stroke
			(width 0)
			(type default)
		)
	)
	(wire
		(pts
			(xy 232.41 261.62) (xy 232.41 262.89)
		)
		(stroke
			(width 0)
			(type default)
		)
	)
	(wire
		(pts
			(xy 118.11 67.31) (xy 118.11 66.04)
		)
		(stroke
			(width 0)
			(type default)
		)
	)
	(wire
		(pts
			(xy 69.85 148.59) (xy 69.85 147.32)
		)
		(stroke
			(width 0)
			(type default)
		)
	)
	(wire
		(pts
			(xy 356.87 127) (xy 365.76 127)
		)
		(stroke
			(width 0)
			(type default)
		)
	)
	(wire
		(pts
			(xy 330.2 127) (xy 340.36 127)
		)
		(stroke
			(width 0)
			(type default)
		)
	)
	(wire
		(pts
			(xy 38.1 67.31) (xy 38.1 66.04)
		)
		(stroke
			(width 0)
			(type default)
		)
	)
	(wire
		(pts
			(xy 355.6 166.37) (xy 355.6 168.91)
		)
		(stroke
			(width 0)
			(type default)
		)
	)
	(wire
		(pts
			(xy 27.94 67.31) (xy 27.94 66.04)
		)
		(stroke
			(width 0)
			(type default)
		)
	)
	(wire
		(pts
			(xy 270.51 241.3) (xy 270.51 238.76)
		)
		(stroke
			(width 0)
			(type default)
		)
	)
	(wire
		(pts
			(xy 369.57 101.6) (xy 369.57 100.33)
		)
		(stroke
			(width 0)
			(type default)
		)
	)
	(wire
		(pts
			(xy 69.85 114.3) (xy 69.85 110.49)
		)
		(stroke
			(width 0)
			(type default)
		)
	)
	(polyline
		(pts
			(xy 337.82 125.73) (xy 337.82 134.62)
		)
		(stroke
			(width 0)
			(type dash)
		)
	)
	(polyline
		(pts
			(xy 266.7 264.16) (xy 281.94 264.16)
		)
		(stroke
			(width 0)
			(type dash)
		)
	)
	(wire
		(pts
			(xy 104.14 120.65) (xy 104.14 119.38)
		)
		(stroke
			(width 0)
			(type default)
		)
	)
	(wire
		(pts
			(xy 269.24 265.43) (xy 269.24 262.89)
		)
		(stroke
			(width 0)
			(type default)
		)
	)
	(wire
		(pts
			(xy 361.95 95.25) (xy 361.95 93.98)
		)
		(stroke
			(width 0)
			(type default)
		)
	)
	(wire
		(pts
			(xy 325.12 93.98) (xy 332.74 93.98)
		)
		(stroke
			(width 0)
			(type default)
		)
	)
	(wire
		(pts
			(xy 29.21 232.41) (xy 34.29 232.41)
		)
		(stroke
			(width 0)
			(type default)
		)
	)
	(wire
		(pts
			(xy 355.6 175.26) (xy 355.6 173.99)
		)
		(stroke
			(width 0)
			(type default)
		)
	)
	(wire
		(pts
			(xy 223.52 119.38) (xy 259.08 119.38)
		)
		(stroke
			(width 0)
			(type default)
		)
	)
	(wire
		(pts
			(xy 246.38 265.43) (xy 246.38 262.89)
		)
		(stroke
			(width 0)
			(type default)
		)
	)
	(wire
		(pts
			(xy 157.48 232.41) (xy 163.83 232.41)
		)
		(stroke
			(width 0)
			(type default)
		)
	)
	(wire
		(pts
			(xy 78.74 173.99) (xy 78.74 172.72)
		)
		(stroke
			(width 0)
			(type default)
		)
	)
	(polyline
		(pts
			(xy 140.97 284.48) (xy 140.97 214.63)
		)
		(stroke
			(width 0)
			(type default)
		)
	)
	(polyline
		(pts
			(xy 34.29 85.09) (xy 34.29 93.98)
		)
		(stroke
			(width 0)
			(type dash)
		)
	)
	(wire
		(pts
			(xy 210.82 273.05) (xy 210.82 271.78)
		)
		(stroke
			(width 0)
			(type default)
		)
	)
	(wire
		(pts
			(xy 339.09 66.04) (xy 339.09 64.77)
		)
		(stroke
			(width 0)
			(type default)
		)
	)
	(wire
		(pts
			(xy 49.53 59.69) (xy 60.96 59.69)
		)
		(stroke
			(width 0)
			(type default)
		)
	)
	(wire
		(pts
			(xy 44.45 148.59) (xy 44.45 147.32)
		)
		(stroke
			(width 0)
			(type default)
		)
	)
	(polyline
		(pts
			(xy 281.94 264.16) (xy 281.94 271.78)
		)
		(stroke
			(width 0)
			(type dash)
		)
	)
	(wire
		(pts
			(xy 34.29 232.41) (xy 34.29 234.95)
		)
		(stroke
			(width 0)
			(type default)
		)
	)
	(wire
		(pts
			(xy 339.09 58.42) (xy 346.71 58.42)
		)
		(stroke
			(width 0)
			(type default)
		)
	)
	(wire
		(pts
			(xy 349.25 127) (xy 349.25 128.27)
		)
		(stroke
			(width 0)
			(type default)
		)
	)
	(wire
		(pts
			(xy 69.85 110.49) (xy 78.74 110.49)
		)
		(stroke
			(width 0)
			(type default)
		)
	)
	(wire
		(pts
			(xy 87.63 198.12) (xy 87.63 196.85)
		)
		(stroke
			(width 0)
			(type default)
		)
	)
	(wire
		(pts
			(xy 60.96 138.43) (xy 69.85 138.43)
		)
		(stroke
			(width 0)
			(type default)
		)
	)
	(wire
		(pts
			(xy 36.83 167.64) (xy 36.83 163.83)
		)
		(stroke
			(width 0)
			(type default)
		)
	)
	(wire
		(pts
			(xy 36.83 86.36) (xy 36.83 87.63)
		)
		(stroke
			(width 0)
			(type default)
		)
	)
	(wire
		(pts
			(xy 276.86 262.89) (xy 276.86 265.43)
		)
		(stroke
			(width 0)
			(type default)
		)
	)
	(wire
		(pts
			(xy 157.48 231.14) (xy 157.48 232.41)
		)
		(stroke
			(width 0)
			(type default)
		)
	)
	(wire
		(pts
			(xy 365.76 134.62) (xy 365.76 133.35)
		)
		(stroke
			(width 0)
			(type default)
		)
	)
	(wire
		(pts
			(xy 104.14 187.96) (xy 111.76 187.96)
		)
		(stroke
			(width 0)
			(type default)
		)
	)
	(polyline
		(pts
			(xy 201.93 265.43) (xy 201.93 271.78)
		)
		(stroke
			(width 0)
			(type dash)
		)
	)
	(wire
		(pts
			(xy 104.14 114.3) (xy 104.14 110.49)
		)
		(stroke
			(width 0)
			(type default)
		)
	)
	(wire
		(pts
			(xy 160.02 262.89) (xy 167.64 262.89)
		)
		(stroke
			(width 0)
			(type default)
		)
	)
	(wire
		(pts
			(xy 27.94 57.15) (xy 27.94 59.69)
		)
		(stroke
			(width 0)
			(type default)
		)
	)
	(polyline
		(pts
			(xy 203.2 233.68) (xy 203.2 240.03)
		)
		(stroke
			(width 0)
			(type dash)
		)
	)
	(wire
		(pts
			(xy 163.83 241.3) (xy 163.83 240.03)
		)
		(stroke
			(width 0)
			(type default)
		)
	)
	(wire
		(pts
			(xy 218.44 232.41) (xy 224.79 232.41)
		)
		(stroke
			(width 0)
			(type default)
		)
	)
	(wire
		(pts
			(xy 332.74 93.98) (xy 340.36 93.98)
		)
		(stroke
			(width 0)
			(type default)
		)
	)
	(wire
		(pts
			(xy 240.03 273.05) (xy 240.03 270.51)
		)
		(stroke
			(width 0)
			(type default)
		)
	)
	(wire
		(pts
			(xy 177.8 234.95) (xy 177.8 232.41)
		)
		(stroke
			(width 0)
			(type default)
		)
	)
	(wire
		(pts
			(xy 330.2 134.62) (xy 330.2 133.35)
		)
		(stroke
			(width 0)
			(type default)
		)
	)
	(wire
		(pts
			(xy 238.76 234.95) (xy 238.76 232.41)
		)
		(stroke
			(width 0)
			(type default)
		)
	)
	(wire
		(pts
			(xy 340.36 93.98) (xy 346.71 93.98)
		)
		(stroke
			(width 0)
			(type default)
		)
	)
	(wire
		(pts
			(xy 118.11 59.69) (xy 127 59.69)
		)
		(stroke
			(width 0)
			(type default)
		)
	)
	(polyline
		(pts
			(xy 245.11 271.78) (xy 237.49 271.78)
		)
		(stroke
			(width 0)
			(type dash)
		)
	)
	(wire
		(pts
			(xy 283.21 100.33) (xy 283.21 121.92)
		)
		(stroke
			(width 0)
			(type default)
		)
	)
	(wire
		(pts
			(xy 269.24 273.05) (xy 269.24 270.51)
		)
		(stroke
			(width 0)
			(type default)
		)
	)
	(wire
		(pts
			(xy 177.8 241.3) (xy 177.8 240.03)
		)
		(stroke
			(width 0)
			(type default)
		)
	)
	(wire
		(pts
			(xy 36.83 93.98) (xy 36.83 92.71)
		)
		(stroke
			(width 0)
			(type default)
		)
	)
	(wire
		(pts
			(xy 78.74 120.65) (xy 78.74 119.38)
		)
		(stroke
			(width 0)
			(type default)
		)
	)
	(wire
		(pts
			(xy 198.12 232.41) (xy 198.12 234.95)
		)
		(stroke
			(width 0)
			(type default)
		)
	)
	(polyline
		(pts
			(xy 189.23 233.68) (xy 189.23 240.03)
		)
		(stroke
			(width 0)
			(type dash)
		)
	)
	(wire
		(pts
			(xy 36.83 120.65) (xy 36.83 119.38)
		)
		(stroke
			(width 0)
			(type default)
		)
	)
	(wire
		(pts
			(xy 325.12 127) (xy 330.2 127)
		)
		(stroke
			(width 0)
			(type default)
		)
	)
	(wire
		(pts
			(xy 345.44 166.37) (xy 336.55 166.37)
		)
		(stroke
			(width 0)
			(type default)
		)
	)
	(wire
		(pts
			(xy 256.54 231.14) (xy 262.89 231.14)
		)
		(stroke
			(width 0)
			(type default)
		)
	)
	(polyline
		(pts
			(xy 161.29 233.68) (xy 168.91 233.68)
		)
		(stroke
			(width 0)
			(type dash)
		)
	)
	(wire
		(pts
			(xy 87.63 191.77) (xy 87.63 187.96)
		)
		(stroke
			(width 0)
			(type default)
		)
	)
	(wire
		(pts
			(xy 62.23 120.65) (xy 62.23 119.38)
		)
		(stroke
			(width 0)
			(type default)
		)
	)
	(wire
		(pts
			(xy 354.33 101.6) (xy 354.33 100.33)
		)
		(stroke
			(width 0)
			(type default)
		)
	)
	(wire
		(pts
			(xy 354.33 66.04) (xy 354.33 64.77)
		)
		(stroke
			(width 0)
			(type default)
		)
	)
	(wire
		(pts
			(xy 340.36 101.6) (xy 340.36 100.33)
		)
		(stroke
			(width 0)
			(type default)
		)
	)
	(polyline
		(pts
			(xy 34.29 83.82) (xy 52.07 83.82)
		)
		(stroke
			(width 0)
			(type dash)
		)
	)
	(wire
		(pts
			(xy 256.54 233.68) (xy 256.54 231.14)
		)
		(stroke
			(width 0)
			(type default)
		)
	)
	(wire
		(pts
			(xy 223.52 132.08) (xy 226.06 132.08)
		)
		(stroke
			(width 0)
			(type default)
		)
	)
	(wire
		(pts
			(xy 102.87 167.64) (xy 102.87 163.83)
		)
		(stroke
			(width 0)
			(type default)
		)
	)
	(polyline
		(pts
			(xy 341.63 166.37) (xy 353.06 166.37)
		)
		(stroke
			(width 0)
			(type dash)
		)
	)
	(polyline
		(pts
			(xy 168.91 233.68) (xy 168.91 240.03)
		)
		(stroke
			(width 0)
			(type dash)
		)
	)
	(wire
		(pts
			(xy 80.01 67.31) (xy 80.01 66.04)
		)
		(stroke
			(width 0)
			(type default)
		)
	)
	(wire
		(pts
			(xy 325.12 134.62) (xy 325.12 133.35)
		)
		(stroke
			(width 0)
			(type default)
		)
	)
	(wire
		(pts
			(xy 223.52 116.84) (xy 269.24 116.84)
		)
		(stroke
			(width 0)
			(type default)
		)
	)
	(wire
		(pts
			(xy 38.1 59.69) (xy 38.1 60.96)
		)
		(stroke
			(width 0)
			(type default)
		)
	)
	(wire
		(pts
			(xy 111.76 114.3) (xy 111.76 110.49)
		)
		(stroke
			(width 0)
			(type default)
		)
	)
	(wire
		(pts
			(xy 88.9 67.31) (xy 88.9 66.04)
		)
		(stroke
			(width 0)
			(type default)
		)
	)
	(wire
		(pts
			(xy 107.95 59.69) (xy 118.11 59.69)
		)
		(stroke
			(width 0)
			(type default)
		)
	)
	(wire
		(pts
			(xy 181.61 127) (xy 182.88 127)
		)
		(stroke
			(width 0)
			(type default)
		)
	)
	(polyline
		(pts
			(xy 254 232.41) (xy 254 240.03)
		)
		(stroke
			(width 0)
			(type dash)
		)
	)
	(wire
		(pts
			(xy 36.83 138.43) (xy 44.45 138.43)
		)
		(stroke
			(width 0)
			(type default)
		)
	)
	(wire
		(pts
			(xy 95.25 110.49) (xy 104.14 110.49)
		)
		(stroke
			(width 0)
			(type default)
		)
	)
	(wire
		(pts
			(xy 336.55 166.37) (xy 336.55 168.91)
		)
		(stroke
			(width 0)
			(type default)
		)
	)
	(wire
		(pts
			(xy 256.54 229.87) (xy 256.54 231.14)
		)
		(stroke
			(width 0)
			(type default)
		)
	)
	(polyline
		(pts
			(xy 237.49 264.16) (xy 245.11 264.16)
		)
		(stroke
			(width 0)
			(type dash)
		)
	)
	(wire
		(pts
			(xy 53.34 138.43) (xy 60.96 138.43)
		)
		(stroke
			(width 0)
			(type default)
		)
	)
	(wire
		(pts
			(xy 361.95 93.98) (xy 369.57 93.98)
		)
		(stroke
			(width 0)
			(type default)
		)
	)
	(polyline
		(pts
			(xy 341.63 166.37) (xy 341.63 175.26)
		)
		(stroke
			(width 0)
			(type dash)
		)
	)
	(wire
		(pts
			(xy 240.03 262.89) (xy 240.03 265.43)
		)
		(stroke
			(width 0)
			(type default)
		)
	)
	(wire
		(pts
			(xy 224.79 241.3) (xy 224.79 240.03)
		)
		(stroke
			(width 0)
			(type default)
		)
	)
	(wire
		(pts
			(xy 69.85 198.12) (xy 69.85 196.85)
		)
		(stroke
			(width 0)
			(type default)
		)
	)
	(wire
		(pts
			(xy 78.74 191.77) (xy 78.74 187.96)
		)
		(stroke
			(width 0)
			(type default)
		)
	)
	(wire
		(pts
			(xy 44.45 138.43) (xy 53.34 138.43)
		)
		(stroke
			(width 0)
			(type default)
		)
	)
	(wire
		(pts
			(xy 336.55 175.26) (xy 336.55 173.99)
		)
		(stroke
			(width 0)
			(type default)
		)
	)
	(wire
		(pts
			(xy 78.74 148.59) (xy 78.74 147.32)
		)
		(stroke
			(width 0)
			(type default)
		)
	)
	(polyline
		(pts
			(xy 161.29 233.68) (xy 161.29 240.03)
		)
		(stroke
			(width 0)
			(type dash)
		)
	)
	(wire
		(pts
			(xy 210.82 264.16) (xy 210.82 266.7)
		)
		(stroke
			(width 0)
			(type default)
		)
	)
	(wire
		(pts
			(xy 340.36 93.98) (xy 340.36 95.25)
		)
		(stroke
			(width 0)
			(type default)
		)
	)
	(wire
		(pts
			(xy 346.71 93.98) (xy 354.33 93.98)
		)
		(stroke
			(width 0)
			(type default)
		)
	)
	(wire
		(pts
			(xy 36.83 110.49) (xy 45.72 110.49)
		)
		(stroke
			(width 0)
			(type default)
		)
	)
	(wire
		(pts
			(xy 181.61 114.3) (xy 182.88 114.3)
		)
		(stroke
			(width 0)
			(type default)
		)
	)
	(polyline
		(pts
			(xy 281.94 271.78) (xy 266.7 271.78)
		)
		(stroke
			(width 0)
			(type dash)
		)
	)
	(wire
		(pts
			(xy 69.85 142.24) (xy 69.85 138.43)
		)
		(stroke
			(width 0)
			(type default)
		)
	)
	(wire
		(pts
			(xy 325.12 93.98) (xy 325.12 95.25)
		)
		(stroke
			(width 0)
			(type default)
		)
	)
	(wire
		(pts
			(xy 238.76 232.41) (xy 232.41 232.41)
		)
		(stroke
			(width 0)
			(type default)
		)
	)
	(wire
		(pts
			(xy 36.83 186.69) (xy 36.83 187.96)
		)
		(stroke
			(width 0)
			(type default)
		)
	)
	(wire
		(pts
			(xy 86.36 173.99) (xy 86.36 172.72)
		)
		(stroke
			(width 0)
			(type default)
		)
	)
	(wire
		(pts
			(xy 346.71 59.69) (xy 346.71 58.42)
		)
		(stroke
			(width 0)
			(type default)
		)
	)
	(wire
		(pts
			(xy 87.63 120.65) (xy 87.63 119.38)
		)
		(stroke
			(width 0)
			(type default)
		)
	)
	(wire
		(pts
			(xy 102.87 142.24) (xy 102.87 138.43)
		)
		(stroke
			(width 0)
			(type default)
		)
	)
	(wire
		(pts
			(xy 269.24 113.03) (xy 269.24 114.3)
		)
		(stroke
			(width 0)
			(type default)
		)
	)
	(wire
		(pts
			(xy 67.31 242.57) (xy 67.31 241.3)
		)
		(stroke
			(width 0)
			(type default)
		)
	)
	(polyline
		(pts
			(xy 245.11 264.16) (xy 245.11 271.78)
		)
		(stroke
			(width 0)
			(type dash)
		)
	)
	(polyline
		(pts
			(xy 27.94 231.14) (xy 46.99 231.14)
		)
		(stroke
			(width 0)
			(type dash)
		)
	)
	(wire
		(pts
			(xy 328.93 66.04) (xy 328.93 64.77)
		)
		(stroke
			(width 0)
			(type default)
		)
	)
	(wire
		(pts
			(xy 36.83 83.82) (xy 36.83 86.36)
		)
		(stroke
			(width 0)
			(type default)
		)
	)
	(wire
		(pts
			(xy 45.72 120.65) (xy 45.72 119.38)
		)
		(stroke
			(width 0)
			(type default)
		)
	)
	(wire
		(pts
			(xy 375.92 58.42) (xy 375.92 59.69)
		)
		(stroke
			(width 0)
			(type default)
		)
	)
	(wire
		(pts
			(xy 87.63 187.96) (xy 95.25 187.96)
		)
		(stroke
			(width 0)
			(type default)
		)
	)
	(wire
		(pts
			(xy 62.23 187.96) (xy 69.85 187.96)
		)
		(stroke
			(width 0)
			(type default)
		)
	)
	(wire
		(pts
			(xy 71.12 59.69) (xy 80.01 59.69)
		)
		(stroke
			(width 0)
			(type default)
		)
	)
	(wire
		(pts
			(xy 369.57 93.98) (xy 369.57 95.25)
		)
		(stroke
			(width 0)
			(type default)
		)
	)
	(wire
		(pts
			(xy 95.25 120.65) (xy 95.25 119.38)
		)
		(stroke
			(width 0)
			(type default)
		)
	)
	(wire
		(pts
			(xy 69.85 187.96) (xy 78.74 187.96)
		)
		(stroke
			(width 0)
			(type default)
		)
	)
	(wire
		(pts
			(xy 60.96 173.99) (xy 60.96 172.72)
		)
		(stroke
			(width 0)
			(type default)
		)
	)
	(wire
		(pts
			(xy 78.74 110.49) (xy 87.63 110.49)
		)
		(stroke
			(width 0)
			(type default)
		)
	)
	(wire
		(pts
			(xy 346.71 95.25) (xy 346.71 93.98)
		)
		(stroke
			(width 0)
			(type default)
		)
	)
	(wire
		(pts
			(xy 325.12 101.6) (xy 325.12 100.33)
		)
		(stroke
			(width 0)
			(type default)
		)
	)
	(polyline
		(pts
			(xy 172.72 270.51) (xy 157.48 270.51)
		)
		(stroke
			(width 0)
			(type dash)
		)
	)
	(wire
		(pts
			(xy 49.53 59.69) (xy 49.53 60.96)
		)
		(stroke
			(width 0)
			(type default)
		)
	)
	(wire
		(pts
			(xy 87.63 114.3) (xy 87.63 110.49)
		)
		(stroke
			(width 0)
			(type default)
		)
	)
	(wire
		(pts
			(xy 204.47 264.16) (xy 210.82 264.16)
		)
		(stroke
			(width 0)
			(type default)
		)
	)
	(wire
		(pts
			(xy 111.76 191.77) (xy 111.76 187.96)
		)
		(stroke
			(width 0)
			(type default)
		)
	)
	(wire
		(pts
			(xy 62.23 110.49) (xy 69.85 110.49)
		)
		(stroke
			(width 0)
			(type default)
		)
	)
	(wire
		(pts
			(xy 224.79 100.33) (xy 224.79 111.76)
		)
		(stroke
			(width 0)
			(type default)
		)
	)
	(polyline
		(pts
			(xy 237.49 264.16) (xy 237.49 271.78)
		)
		(stroke
			(width 0)
			(type dash)
		)
	)
	(wire
		(pts
			(xy 340.36 124.46) (xy 340.36 127)
		)
		(stroke
			(width 0)
			(type default)
		)
	)
	(wire
		(pts
			(xy 328.93 58.42) (xy 328.93 59.69)
		)
		(stroke
			(width 0)
			(type default)
		)
	)
	(polyline
		(pts
			(xy 46.99 241.3) (xy 26.67 241.3)
		)
		(stroke
			(width 0)
			(type dash)
		)
	)
	(wire
		(pts
			(xy 368.3 59.69) (xy 368.3 58.42)
		)
		(stroke
			(width 0)
			(type default)
		)
	)
	(wire
		(pts
			(xy 78.74 142.24) (xy 78.74 138.43)
		)
		(stroke
			(width 0)
			(type default)
		)
	)
	(wire
		(pts
			(xy 29.21 232.41) (xy 29.21 234.95)
		)
		(stroke
			(width 0)
			(type default)
		)
	)
	(wire
		(pts
			(xy 191.77 234.95) (xy 191.77 232.41)
		)
		(stroke
			(width 0)
			(type default)
		)
	)
	(wire
		(pts
			(xy 181.61 111.76) (xy 182.88 111.76)
		)
		(stroke
			(width 0)
			(type default)
		)
	)
	(wire
		(pts
			(xy 69.85 138.43) (xy 78.74 138.43)
		)
		(stroke
			(width 0)
			(type default)
		)
	)
	(wire
		(pts
			(xy 95.25 187.96) (xy 104.14 187.96)
		)
		(stroke
			(width 0)
			(type default)
		)
	)
	(wire
		(pts
			(xy 36.83 107.95) (xy 36.83 110.49)
		)
		(stroke
			(width 0)
			(type default)
		)
	)
	(wire
		(pts
			(xy 191.77 231.14) (xy 191.77 232.41)
		)
		(stroke
			(width 0)
			(type default)
		)
	)
	(wire
		(pts
			(xy 240.03 262.89) (xy 246.38 262.89)
		)
		(stroke
			(width 0)
			(type default)
		)
	)
	(wire
		(pts
			(xy 62.23 191.77) (xy 62.23 187.96)
		)
		(stroke
			(width 0)
			(type default)
		)
	)
	(wire
		(pts
			(xy 62.23 114.3) (xy 62.23 110.49)
		)
		(stroke
			(width 0)
			(type default)
		)
	)
	(wire
		(pts
			(xy 276.86 241.3) (xy 276.86 238.76)
		)
		(stroke
			(width 0)
			(type default)
		)
	)
	(wire
		(pts
			(xy 45.72 110.49) (xy 53.34 110.49)
		)
		(stroke
			(width 0)
			(type default)
		)
	)
	(wire
		(pts
			(xy 274.32 121.92) (xy 274.32 120.65)
		)
		(stroke
			(width 0)
			(type default)
		)
	)
	(wire
		(pts
			(xy 102.87 138.43) (xy 111.76 138.43)
		)
		(stroke
			(width 0)
			(type default)
		)
	)
	(polyline
		(pts
			(xy 229.87 240.03) (xy 222.25 240.03)
		)
		(stroke
			(width 0)
			(type dash)
		)
	)
	(wire
		(pts
			(xy 274.32 121.92) (xy 283.21 121.92)
		)
		(stroke
			(width 0)
			(type default)
		)
	)
	(polyline
		(pts
			(xy 229.87 233.68) (xy 229.87 240.03)
		)
		(stroke
			(width 0)
			(type dash)
		)
	)
	(polyline
		(pts
			(xy 344.17 66.04) (xy 336.55 66.04)
		)
		(stroke
			(width 0)
			(type dash)
		)
	)
	(wire
		(pts
			(xy 365.76 127) (xy 365.76 128.27)
		)
		(stroke
			(width 0)
			(type default)
		)
	)
	(wire
		(pts
			(xy 274.32 114.3) (xy 274.32 115.57)
		)
		(stroke
			(width 0)
			(type default)
		)
	)
	(wire
		(pts
			(xy 340.36 134.62) (xy 340.36 133.35)
		)
		(stroke
			(width 0)
			(type default)
		)
	)
	(polyline
		(pts
			(xy 299.72 11.43) (xy 299.72 252.73)
		)
		(stroke
			(width 0)
			(type default)
		)
	)
	(wire
		(pts
			(xy 346.71 66.04) (xy 346.71 64.77)
		)
		(stroke
			(width 0)
			(type default)
		)
	)
	(wire
		(pts
			(xy 50.8 232.41) (xy 58.42 232.41)
		)
		(stroke
			(width 0)
			(type default)
		)
	)
	(wire
		(pts
			(xy 204.47 273.05) (xy 204.47 271.78)
		)
		(stroke
			(width 0)
			(type default)
		)
	)
	(wire
		(pts
			(xy 167.64 262.89) (xy 173.99 262.89)
		)
		(stroke
			(width 0)
			(type default)
		)
	)
	(wire
		(pts
			(xy 276.86 231.14) (xy 270.51 231.14)
		)
		(stroke
			(width 0)
			(type default)
		)
	)
	(wire
		(pts
			(xy 205.74 241.3) (xy 205.74 240.03)
		)
		(stroke
			(width 0)
			(type default)
		)
	)
	(wire
		(pts
			(xy 356.87 134.62) (xy 356.87 133.35)
		)
		(stroke
			(width 0)
			(type default)
		)
	)
	(wire
		(pts
			(xy 173.99 119.38) (xy 173.99 121.92)
		)
		(stroke
			(width 0)
			(type default)
		)
	)
	(wire
		(pts
			(xy 181.61 271.78) (xy 181.61 270.51)
		)
		(stroke
			(width 0)
			(type default)
		)
	)
	(wire
		(pts
			(xy 368.3 66.04) (xy 368.3 64.77)
		)
		(stroke
			(width 0)
			(type default)
		)
	)
	(wire
		(pts
			(xy 368.3 58.42) (xy 375.92 58.42)
		)
		(stroke
			(width 0)
			(type default)
		)
	)
	(wire
		(pts
			(xy 27.94 59.69) (xy 27.94 60.96)
		)
		(stroke
			(width 0)
			(type default)
		)
	)
	(wire
		(pts
			(xy 325.12 127) (xy 325.12 128.27)
		)
		(stroke
			(width 0)
			(type default)
		)
	)
	(wire
		(pts
			(xy 171.45 234.95) (xy 171.45 232.41)
		)
		(stroke
			(width 0)
			(type default)
		)
	)
	(wire
		(pts
			(xy 345.44 166.37) (xy 345.44 168.91)
		)
		(stroke
			(width 0)
			(type default)
		)
	)
	(wire
		(pts
			(xy 205.74 234.95) (xy 205.74 232.41)
		)
		(stroke
			(width 0)
			(type default)
		)
	)
	(wire
		(pts
			(xy 53.34 198.12) (xy 53.34 196.85)
		)
		(stroke
			(width 0)
			(type default)
		)
	)
	(polyline
		(pts
			(xy 353.06 166.37) (xy 353.06 175.26)
		)
		(stroke
			(width 0)
			(type dash)
		)
	)
	(wire
		(pts
			(xy 349.25 134.62) (xy 349.25 133.35)
		)
		(stroke
			(width 0)
			(type default)
		)
	)
	(wire
		(pts
			(xy 127 59.69) (xy 127 60.96)
		)
		(stroke
			(width 0)
			(type default)
		)
	)
	(polyline
		(pts
			(xy 168.91 240.03) (xy 161.29 240.03)
		)
		(stroke
			(width 0)
			(type dash)
		)
	)
	(wire
		(pts
			(xy 53.34 142.24) (xy 53.34 138.43)
		)
		(stroke
			(width 0)
			(type default)
		)
	)
	(wire
		(pts
			(xy 102.87 173.99) (xy 102.87 172.72)
		)
		(stroke
			(width 0)
			(type default)
		)
	)
	(wire
		(pts
			(xy 163.83 232.41) (xy 171.45 232.41)
		)
		(stroke
			(width 0)
			(type default)
		)
	)
	(wire
		(pts
			(xy 60.96 59.69) (xy 60.96 60.96)
		)
		(stroke
			(width 0)
			(type default)
		)
	)
	(wire
		(pts
			(xy 223.52 114.3) (xy 242.57 114.3)
		)
		(stroke
			(width 0)
			(type default)
		)
	)
	(wire
		(pts
			(xy 173.99 137.16) (xy 182.88 137.16)
		)
		(stroke
			(width 0)
			(type default)
		)
	)
	(wire
		(pts
			(xy 191.77 241.3) (xy 191.77 240.03)
		)
		(stroke
			(width 0)
			(type default)
		)
	)
	(wire
		(pts
			(xy 67.31 236.22) (xy 67.31 232.41)
		)
		(stroke
			(width 0)
			(type default)
		)
	)
	(polyline
		(pts
			(xy 344.17 57.15) (xy 344.17 66.04)
		)
		(stroke
			(width 0)
			(type dash)
		)
	)
	(wire
		(pts
			(xy 345.44 165.1) (xy 345.44 166.37)
		)
		(stroke
			(width 0)
			(type default)
		)
	)
	(wire
		(pts
			(xy 332.74 101.6) (xy 332.74 100.33)
		)
		(stroke
			(width 0)
			(type default)
		)
	)
	(wire
		(pts
			(xy 269.24 114.3) (xy 269.24 116.84)
		)
		(stroke
			(width 0)
			(type default)
		)
	)
	(wire
		(pts
			(xy 60.96 167.64) (xy 60.96 163.83)
		)
		(stroke
			(width 0)
			(type default)
		)
	)
	(polyline
		(pts
			(xy 222.25 233.68) (xy 222.25 240.03)
		)
		(stroke
			(width 0)
			(type dash)
		)
	)
	(wire
		(pts
			(xy 339.09 58.42) (xy 339.09 59.69)
		)
		(stroke
			(width 0)
			(type default)
		)
	)
	(wire
		(pts
			(xy 375.92 66.04) (xy 375.92 64.77)
		)
		(stroke
			(width 0)
			(type default)
		)
	)
	(wire
		(pts
			(xy 232.41 234.95) (xy 232.41 232.41)
		)
		(stroke
			(width 0)
			(type default)
		)
	)
	(wire
		(pts
			(xy 171.45 241.3) (xy 171.45 240.03)
		)
		(stroke
			(width 0)
			(type default)
		)
	)
	(wire
		(pts
			(xy 223.52 137.16) (xy 226.06 137.16)
		)
		(stroke
			(width 0)
			(type default)
		)
	)
	(wire
		(pts
			(xy 224.79 232.41) (xy 232.41 232.41)
		)
		(stroke
			(width 0)
			(type default)
		)
	)
	(wire
		(pts
			(xy 99.06 67.31) (xy 99.06 66.04)
		)
		(stroke
			(width 0)
			(type default)
		)
	)
	(wire
		(pts
			(xy 69.85 120.65) (xy 69.85 119.38)
		)
		(stroke
			(width 0)
			(type default)
		)
	)
	(wire
		(pts
			(xy 242.57 114.3) (xy 242.57 100.33)
		)
		(stroke
			(width 0)
			(type default)
		)
	)
	(wire
		(pts
			(xy 204.47 266.7) (xy 204.47 264.16)
		)
		(stroke
			(width 0)
			(type default)
		)
	)
	(wire
		(pts
			(xy 107.95 67.31) (xy 107.95 66.04)
		)
		(stroke
			(width 0)
			(type default)
		)
	)
	(wire
		(pts
			(xy 118.11 59.69) (xy 118.11 60.96)
		)
		(stroke
			(width 0)
			(type default)
		)
	)
	(wire
		(pts
			(xy 181.61 111.76) (xy 181.61 114.3)
		)
		(stroke
			(width 0)
			(type default)
		)
	)
	(wire
		(pts
			(xy 270.51 233.68) (xy 270.51 231.14)
		)
		(stroke
			(width 0)
			(type default)
		)
	)
	(wire
		(pts
			(xy 78.74 167.64) (xy 78.74 163.83)
		)
		(stroke
			(width 0)
			(type default)
		)
	)
	(polyline
		(pts
			(xy 157.48 264.16) (xy 157.48 270.51)
		)
		(stroke
			(width 0)
			(type dash)
		)
	)
	(wire
		(pts
			(xy 269.24 114.3) (xy 274.32 114.3)
		)
		(stroke
			(width 0)
			(type default)
		)
	)
	(polyline
		(pts
			(xy 346.71 134.62) (xy 337.82 134.62)
		)
		(stroke
			(width 0)
			(type dash)
		)
	)
	(wire
		(pts
			(xy 173.99 132.08) (xy 173.99 137.16)
		)
		(stroke
			(width 0)
			(type default)
		)
	)
	(wire
		(pts
			(xy 95.25 148.59) (xy 95.25 147.32)
		)
		(stroke
			(width 0)
			(type default)
		)
	)
	(wire
		(pts
			(xy 262.89 241.3) (xy 262.89 238.76)
		)
		(stroke
			(width 0)
			(type default)
		)
	)
	(polyline
		(pts
			(xy 222.25 233.68) (xy 229.87 233.68)
		)
		(stroke
			(width 0)
			(type dash)
		)
	)
	(wire
		(pts
			(xy 104.14 191.77) (xy 104.14 187.96)
		)
		(stroke
			(width 0)
			(type default)
		)
	)
	(wire
		(pts
			(xy 246.38 273.05) (xy 246.38 270.51)
		)
		(stroke
			(width 0)
			(type default)
		)
	)
	(wire
		(pts
			(xy 354.33 93.98) (xy 361.95 93.98)
		)
		(stroke
			(width 0)
			(type default)
		)
	)
	(wire
		(pts
			(xy 71.12 59.69) (xy 71.12 60.96)
		)
		(stroke
			(width 0)
			(type default)
		)
	)
	(wire
		(pts
			(xy 78.74 187.96) (xy 87.63 187.96)
		)
		(stroke
			(width 0)
			(type default)
		)
	)
	(wire
		(pts
			(xy 69.85 167.64) (xy 69.85 163.83)
		)
		(stroke
			(width 0)
			(type default)
		)
	)
	(wire
		(pts
			(xy 87.63 110.49) (xy 95.25 110.49)
		)
		(stroke
			(width 0)
			(type default)
		)
	)
	(wire
		(pts
			(xy 373.38 134.62) (xy 373.38 133.35)
		)
		(stroke
			(width 0)
			(type default)
		)
	)
	(wire
		(pts
			(xy 27.94 59.69) (xy 38.1 59.69)
		)
		(stroke
			(width 0)
			(type default)
		)
	)
	(wire
		(pts
			(xy 330.2 127) (xy 330.2 128.27)
		)
		(stroke
			(width 0)
			(type default)
		)
	)
	(polyline
		(pts
			(xy 172.72 264.16) (xy 172.72 270.51)
		)
		(stroke
			(width 0)
			(type dash)
		)
	)
	(wire
		(pts
			(xy 86.36 148.59) (xy 86.36 147.32)
		)
		(stroke
			(width 0)
			(type default)
		)
	)
	(wire
		(pts
			(xy 226.06 137.16) (xy 226.06 149.86)
		)
		(stroke
			(width 0)
			(type default)
		)
	)
	(wire
		(pts
			(xy 361.95 58.42) (xy 368.3 58.42)
		)
		(stroke
			(width 0)
			(type default)
		)
	)
	(wire
		(pts
			(xy 256.54 241.3) (xy 256.54 238.76)
		)
		(stroke
			(width 0)
			(type default)
		)
	)
	(wire
		(pts
			(xy 36.83 114.3) (xy 36.83 110.49)
		)
		(stroke
			(width 0)
			(type default)
		)
	)
	(polyline
		(pts
			(xy 337.82 125.73) (xy 346.71 125.73)
		)
		(stroke
			(width 0)
			(type dash)
		)
	)
	(wire
		(pts
			(xy 99.06 59.69) (xy 99.06 60.96)
		)
		(stroke
			(width 0)
			(type default)
		)
	)
	(wire
		(pts
			(xy 173.99 121.92) (xy 173.99 132.08)
		)
		(stroke
			(width 0)
			(type default)
		)
	)
	(wire
		(pts
			(xy 328.93 58.42) (xy 322.58 58.42)
		)
		(stroke
			(width 0)
			(type default)
		)
	)
	(polyline
		(pts
			(xy 189.23 233.68) (xy 203.2 233.68)
		)
		(stroke
			(width 0)
			(type dash)
		)
	)
	(wire
		(pts
			(xy 36.83 142.24) (xy 36.83 138.43)
		)
		(stroke
			(width 0)
			(type default)
		)
	)
	(wire
		(pts
			(xy 107.95 59.69) (xy 107.95 60.96)
		)
		(stroke
			(width 0)
			(type default)
		)
	)
	(wire
		(pts
			(xy 38.1 59.69) (xy 49.53 59.69)
		)
		(stroke
			(width 0)
			(type default)
		)
	)
	(wire
		(pts
			(xy 226.06 134.62) (xy 226.06 137.16)
		)
		(stroke
			(width 0)
			(type default)
		)
	)
	(wire
		(pts
			(xy 181.61 100.33) (xy 181.61 111.76)
		)
		(stroke
			(width 0)
			(type default)
		)
	)
	(wire
		(pts
			(xy 269.24 262.89) (xy 276.86 262.89)
		)
		(stroke
			(width 0)
			(type default)
		)
	)
	(wire
		(pts
			(xy 36.83 86.36) (xy 44.45 86.36)
		)
		(stroke
			(width 0)
			(type default)
		)
	)
	(wire
		(pts
			(xy 44.45 167.64) (xy 44.45 163.83)
		)
		(stroke
			(width 0)
			(type default)
		)
	)
	(wire
		(pts
			(xy 339.09 58.42) (xy 328.93 58.42)
		)
		(stroke
			(width 0)
			(type default)
		)
	)
	(polyline
		(pts
			(xy 59.69 57.15) (xy 134.62 57.15)
		)
		(stroke
			(width 0)
			(type dash)
		)
	)
	(wire
		(pts
			(xy 86.36 138.43) (xy 95.25 138.43)
		)
		(stroke
			(width 0)
			(type default)
		)
	)
	(polyline
		(pts
			(xy 52.07 93.98) (xy 34.29 93.98)
		)
		(stroke
			(width 0)
			(type dash)
		)
	)
	(wire
		(pts
			(xy 95.25 167.64) (xy 95.25 163.83)
		)
		(stroke
			(width 0)
			(type default)
		)
	)
	(wire
		(pts
			(xy 36.83 187.96) (xy 53.34 187.96)
		)
		(stroke
			(width 0)
			(type default)
		)
	)
	(wire
		(pts
			(xy 346.71 101.6) (xy 346.71 100.33)
		)
		(stroke
			(width 0)
			(type default)
		)
	)
	(wire
		(pts
			(xy 53.34 191.77) (xy 53.34 187.96)
		)
		(stroke
			(width 0)
			(type default)
		)
	)
	(wire
		(pts
			(xy 325.12 91.44) (xy 325.12 93.98)
		)
		(stroke
			(width 0)
			(type default)
		)
	)
	(wire
		(pts
			(xy 34.29 242.57) (xy 34.29 240.03)
		)
		(stroke
			(width 0)
			(type default)
		)
	)
	(wire
		(pts
			(xy 49.53 67.31) (xy 49.53 66.04)
		)
		(stroke
			(width 0)
			(type default)
		)
	)
	(wire
		(pts
			(xy 58.42 236.22) (xy 58.42 232.41)
		)
		(stroke
			(width 0)
			(type default)
		)
	)
	(wire
		(pts
			(xy 53.34 163.83) (xy 60.96 163.83)
		)
		(stroke
			(width 0)
			(type default)
		)
	)
	(wire
		(pts
			(xy 78.74 138.43) (xy 86.36 138.43)
		)
		(stroke
			(width 0)
			(type default)
		)
	)
	(wire
		(pts
			(xy 95.25 138.43) (xy 102.87 138.43)
		)
		(stroke
			(width 0)
			(type default)
		)
	)
	(wire
		(pts
			(xy 173.99 100.33) (xy 173.99 119.38)
		)
		(stroke
			(width 0)
			(type default)
		)
	)
	(wire
		(pts
			(xy 223.52 121.92) (xy 274.32 121.92)
		)
		(stroke
			(width 0)
			(type default)
		)
	)
	(wire
		(pts
			(xy 218.44 231.14) (xy 218.44 232.41)
		)
		(stroke
			(width 0)
			(type default)
		)
	)
	(wire
		(pts
			(xy 95.25 114.3) (xy 95.25 110.49)
		)
		(stroke
			(width 0)
			(type default)
		)
	)
	(wire
		(pts
			(xy 104.14 110.49) (xy 111.76 110.49)
		)
		(stroke
			(width 0)
			(type default)
		)
	)
	(wire
		(pts
			(xy 36.83 162.56) (xy 36.83 163.83)
		)
		(stroke
			(width 0)
			(type default)
		)
	)
	(wire
		(pts
			(xy 322.58 66.04) (xy 322.58 64.77)
		)
		(stroke
			(width 0)
			(type default)
		)
	)
	(wire
		(pts
			(xy 173.99 121.92) (xy 182.88 121.92)
		)
		(stroke
			(width 0)
			(type default)
		)
	)
	(wire
		(pts
			(xy 36.83 148.59) (xy 36.83 147.32)
		)
		(stroke
			(width 0)
			(type default)
		)
	)
	(wire
		(pts
			(xy 198.12 241.3) (xy 198.12 240.03)
		)
		(stroke
			(width 0)
			(type default)
		)
	)
	(wire
		(pts
			(xy 365.76 127) (xy 373.38 127)
		)
		(stroke
			(width 0)
			(type default)
		)
	)
	(wire
		(pts
			(xy 276.86 273.05) (xy 276.86 270.51)
		)
		(stroke
			(width 0)
			(type default)
		)
	)
	(wire
		(pts
			(xy 340.36 127) (xy 349.25 127)
		)
		(stroke
			(width 0)
			(type default)
		)
	)
	(wire
		(pts
			(xy 269.24 261.62) (xy 269.24 262.89)
		)
		(stroke
			(width 0)
			(type default)
		)
	)
	(wire
		(pts
			(xy 181.61 265.43) (xy 181.61 262.89)
		)
		(stroke
			(width 0)
			(type default)
		)
	)
	(polyline
		(pts
			(xy 353.06 175.26) (xy 341.63 175.26)
		)
		(stroke
			(width 0)
			(type dash)
		)
	)
	(wire
		(pts
			(xy 204.47 262.89) (xy 204.47 264.16)
		)
		(stroke
			(width 0)
			(type default)
		)
	)
	(wire
		(pts
			(xy 60.96 163.83) (xy 69.85 163.83)
		)
		(stroke
			(width 0)
			(type default)
		)
	)
	(wire
		(pts
			(xy 340.36 127) (xy 340.36 128.27)
		)
		(stroke
			(width 0)
			(type default)
		)
	)
	(wire
		(pts
			(xy 361.95 101.6) (xy 361.95 100.33)
		)
		(stroke
			(width 0)
			(type default)
		)
	)
	(wire
		(pts
			(xy 95.25 142.24) (xy 95.25 138.43)
		)
		(stroke
			(width 0)
			(type default)
		)
	)
	(wire
		(pts
			(xy 332.74 93.98) (xy 332.74 95.25)
		)
		(stroke
			(width 0)
			(type default)
		)
	)
	(polyline
		(pts
			(xy 46.99 231.14) (xy 46.99 241.3)
		)
		(stroke
			(width 0)
			(type dash)
		)
	)
	(wire
		(pts
			(xy 53.34 187.96) (xy 62.23 187.96)
		)
		(stroke
			(width 0)
			(type default)
		)
	)
	(wire
		(pts
			(xy 88.9 59.69) (xy 99.06 59.69)
		)
		(stroke
			(width 0)
			(type default)
		)
	)
	(wire
		(pts
			(xy 160.02 271.78) (xy 160.02 269.24)
		)
		(stroke
			(width 0)
			(type default)
		)
	)
	(wire
		(pts
			(xy 99.06 59.69) (xy 107.95 59.69)
		)
		(stroke
			(width 0)
			(type default)
		)
	)
	(wire
		(pts
			(xy 40.64 242.57) (xy 40.64 240.03)
		)
		(stroke
			(width 0)
			(type default)
		)
	)
	(polyline
		(pts
			(xy 201.93 265.43) (xy 215.9 265.43)
		)
		(stroke
			(width 0)
			(type dash)
		)
	)
	(wire
		(pts
			(xy 53.34 167.64) (xy 53.34 163.83)
		)
		(stroke
			(width 0)
			(type default)
		)
	)
	(wire
		(pts
			(xy 60.96 148.59) (xy 60.96 147.32)
		)
		(stroke
			(width 0)
			(type default)
		)
	)
	(wire
		(pts
			(xy 181.61 114.3) (xy 181.61 127)
		)
		(stroke
			(width 0)
			(type default)
		)
	)
	(wire
		(pts
			(xy 339.09 55.88) (xy 339.09 58.42)
		)
		(stroke
			(width 0)
			(type default)
		)
	)
	(wire
		(pts
			(xy 191.77 232.41) (xy 198.12 232.41)
		)
		(stroke
			(width 0)
			(type default)
		)
	)
	(wire
		(pts
			(xy 111.76 120.65) (xy 111.76 119.38)
		)
		(stroke
			(width 0)
			(type default)
		)
	)
	(wire
		(pts
			(xy 361.95 58.42) (xy 361.95 59.69)
		)
		(stroke
			(width 0)
			(type default)
		)
	)
	(polyline
		(pts
			(xy 267.97 240.03) (xy 254 240.03)
		)
		(stroke
			(width 0)
			(type dash)
		)
	)
	(wire
		(pts
			(xy 50.8 242.57) (xy 50.8 241.3)
		)
		(stroke
			(width 0)
			(type default)
		)
	)
	(wire
		(pts
			(xy 40.64 232.41) (xy 50.8 232.41)
		)
		(stroke
			(width 0)
			(type default)
		)
	)
	(wire
		(pts
			(xy 88.9 59.69) (xy 88.9 60.96)
		)
		(stroke
			(width 0)
			(type default)
		)
	)
	(wire
		(pts
			(xy 50.8 236.22) (xy 50.8 232.41)
		)
		(stroke
			(width 0)
			(type default)
		)
	)
	(wire
		(pts
			(xy 78.74 114.3) (xy 78.74 110.49)
		)
		(stroke
			(width 0)
			(type default)
		)
	)
	(wire
		(pts
			(xy 95.25 173.99) (xy 95.25 172.72)
		)
		(stroke
			(width 0)
			(type default)
		)
	)
	(polyline
		(pts
			(xy 12.7 214.63) (xy 140.97 214.63)
		)
		(stroke
			(width 0)
			(type default)
		)
	)
	(wire
		(pts
			(xy 346.71 58.42) (xy 354.33 58.42)
		)
		(stroke
			(width 0)
			(type default)
		)
	)
	(polyline
		(pts
			(xy 140.97 11.43) (xy 140.97 214.63)
		)
		(stroke
			(width 0)
			(type default)
		)
	)
	(wire
		(pts
			(xy 53.34 148.59) (xy 53.34 147.32)
		)
		(stroke
			(width 0)
			(type default)
		)
	)
	(wire
		(pts
			(xy 44.45 173.99) (xy 44.45 172.72)
		)
		(stroke
			(width 0)
			(type default)
		)
	)
	(wire
		(pts
			(xy 58.42 232.41) (xy 67.31 232.41)
		)
		(stroke
			(width 0)
			(type default)
		)
	)
	(polyline
		(pts
			(xy 59.69 67.31) (xy 134.62 67.31)
		)
		(stroke
			(width 0)
			(type dash)
		)
	)
	(wire
		(pts
			(xy 167.64 271.78) (xy 167.64 270.51)
		)
		(stroke
			(width 0)
			(type default)
		)
	)
	(polyline
		(pts
			(xy 203.2 240.03) (xy 189.23 240.03)
		)
		(stroke
			(width 0)
			(type dash)
		)
	)
	(wire
		(pts
			(xy 53.34 110.49) (xy 62.23 110.49)
		)
		(stroke
			(width 0)
			(type default)
		)
	)
	(polyline
		(pts
			(xy 336.55 57.15) (xy 344.17 57.15)
		)
		(stroke
			(width 0)
			(type dash)
		)
	)
	(wire
		(pts
			(xy 80.01 59.69) (xy 88.9 59.69)
		)
		(stroke
			(width 0)
			(type default)
		)
	)
	(wire
		(pts
			(xy 356.87 128.27) (xy 356.87 127)
		)
		(stroke
			(width 0)
			(type default)
		)
	)
	(polyline
		(pts
			(xy 26.67 241.3) (xy 26.67 231.14)
		)
		(stroke
			(width 0)
			(type dash)
		)
	)
	(wire
		(pts
			(xy 69.85 191.77) (xy 69.85 187.96)
		)
		(stroke
			(width 0)
			(type default)
		)
	)
	(wire
		(pts
			(xy 238.76 241.3) (xy 238.76 240.03)
		)
		(stroke
			(width 0)
			(type default)
		)
	)
	(wire
		(pts
			(xy 95.25 198.12) (xy 95.25 196.85)
		)
		(stroke
			(width 0)
			(type default)
		)
	)
	(wire
		(pts
			(xy 60.96 142.24) (xy 60.96 138.43)
		)
		(stroke
			(width 0)
			(type default)
		)
	)
	(wire
		(pts
			(xy 173.99 119.38) (xy 182.88 119.38)
		)
		(stroke
			(width 0)
			(type default)
		)
	)
	(wire
		(pts
			(xy 111.76 173.99) (xy 111.76 172.72)
		)
		(stroke
			(width 0)
			(type default)
		)
	)
	(wire
		(pts
			(xy 111.76 148.59) (xy 111.76 147.32)
		)
		(stroke
			(width 0)
			(type default)
		)
	)
	(wire
		(pts
			(xy 224.79 232.41) (xy 224.79 234.95)
		)
		(stroke
			(width 0)
			(type default)
		)
	)
	(wire
		(pts
			(xy 29.21 242.57) (xy 29.21 240.03)
		)
		(stroke
			(width 0)
			(type default)
		)
	)
	(wire
		(pts
			(xy 36.83 137.16) (xy 36.83 138.43)
		)
		(stroke
			(width 0)
			(type default)
		)
	)
	(polyline
		(pts
			(xy 215.9 271.78) (xy 201.93 271.78)
		)
		(stroke
			(width 0)
			(type dash)
		)
	)
	(wire
		(pts
			(xy 36.83 163.83) (xy 44.45 163.83)
		)
		(stroke
			(width 0)
			(type default)
		)
	)
	(wire
		(pts
			(xy 86.36 142.24) (xy 86.36 138.43)
		)
		(stroke
			(width 0)
			(type default)
		)
	)
	(wire
		(pts
			(xy 173.99 262.89) (xy 181.61 262.89)
		)
		(stroke
			(width 0)
			(type default)
		)
	)
	(wire
		(pts
			(xy 44.45 86.36) (xy 44.45 87.63)
		)
		(stroke
			(width 0)
			(type default)
		)
	)
	(wire
		(pts
			(xy 102.87 163.83) (xy 111.76 163.83)
		)
		(stroke
			(width 0)
			(type default)
		)
	)
	(wire
		(pts
			(xy 349.25 127) (xy 356.87 127)
		)
		(stroke
			(width 0)
			(type default)
		)
	)
	(wire
		(pts
			(xy 223.52 134.62) (xy 226.06 134.62)
		)
		(stroke
			(width 0)
			(type default)
		)
	)
	(wire
		(pts
			(xy 226.06 132.08) (xy 226.06 134.62)
		)
		(stroke
			(width 0)
			(type default)
		)
	)
	(wire
		(pts
			(xy 361.95 66.04) (xy 361.95 64.77)
		)
		(stroke
			(width 0)
			(type default)
		)
	)
	(polyline
		(pts
			(xy 59.69 57.15) (xy 59.69 67.31)
		)
		(stroke
			(width 0)
			(type dash)
		)
	)
	(polyline
		(pts
			(xy 191.77 284.48) (xy 191.77 284.48)
		)
		(stroke
			(width 0)
			(type default)
		)
	)
	(wire
		(pts
			(xy 173.99 271.78) (xy 173.99 270.51)
		)
		(stroke
			(width 0)
			(type default)
		)
	)
	(wire
		(pts
			(xy 262.89 231.14) (xy 270.51 231.14)
		)
		(stroke
			(width 0)
			(type default)
		)
	)
	(wire
		(pts
			(xy 127 67.31) (xy 127 66.04)
		)
		(stroke
			(width 0)
			(type default)
		)
	)
	(polyline
		(pts
			(xy 157.48 264.16) (xy 172.72 264.16)
		)
		(stroke
			(width 0)
			(type dash)
		)
	)
	(wire
		(pts
			(xy 373.38 127) (xy 373.38 128.27)
		)
		(stroke
			(width 0)
			(type default)
		)
	)
	(wire
		(pts
			(xy 262.89 231.14) (xy 262.89 233.68)
		)
		(stroke
			(width 0)
			(type default)
		)
	)
	(wire
		(pts
			(xy 95.25 163.83) (xy 102.87 163.83)
		)
		(stroke
			(width 0)
			(type default)
		)
	)
	(wire
		(pts
			(xy 60.96 59.69) (xy 71.12 59.69)
		)
		(stroke
			(width 0)
			(type default)
		)
	)
	(wire
		(pts
			(xy 322.58 58.42) (xy 322.58 59.69)
		)
		(stroke
			(width 0)
			(type default)
		)
	)
	(polyline
		(pts
			(xy 336.55 66.04) (xy 336.55 57.15)
		)
		(stroke
			(width 0)
			(type dash)
		)
	)
	(wire
		(pts
			(xy 53.34 120.65) (xy 53.34 119.38)
		)
		(stroke
			(width 0)
			(type default)
		)
	)
	(wire
		(pts
			(xy 259.08 100.33) (xy 259.08 119.38)
		)
		(stroke
			(width 0)
			(type default)
		)
	)
	(wire
		(pts
			(xy 232.41 241.3) (xy 232.41 240.03)
		)
		(stroke
			(width 0)
			(type default)
		)
	)
	(wire
		(pts
			(xy 34.29 232.41) (xy 40.64 232.41)
		)
		(stroke
			(width 0)
			(type default)
		)
	)
	(polyline
		(pts
			(xy 140.97 214.63) (xy 299.72 214.63)
		)
		(stroke
			(width 0)
			(type default)
		)
	)
	(wire
		(pts
			(xy 53.34 173.99) (xy 53.34 172.72)
		)
		(stroke
			(width 0)
			(type default)
		)
	)
	(wire
		(pts
			(xy 354.33 93.98) (xy 354.33 95.25)
		)
		(stroke
			(width 0)
			(type default)
		)
	)
	(wire
		(pts
			(xy 45.72 114.3) (xy 45.72 110.49)
		)
		(stroke
			(width 0)
			(type default)
		)
	)
	(wire
		(pts
			(xy 232.41 262.89) (xy 240.03 262.89)
		)
		(stroke
			(width 0)
			(type default)
		)
	)
	(wire
		(pts
			(xy 167.64 262.89) (xy 167.64 265.43)
		)
		(stroke
			(width 0)
			(type default)
		)
	)
	(wire
		(pts
			(xy 95.25 191.77) (xy 95.25 187.96)
		)
		(stroke
			(width 0)
			(type default)
		)
	)
	(wire
		(pts
			(xy 104.14 198.12) (xy 104.14 196.85)
		)
		(stroke
			(width 0)
			(type default)
		)
	)
	(polyline
		(pts
			(xy 26.67 231.14) (xy 27.94 231.14)
		)
		(stroke
			(width 0)
			(type dash)
		)
	)
	(wire
		(pts
			(xy 40.64 232.41) (xy 40.64 234.95)
		)
		(stroke
			(width 0)
			(type default)
		)
	)
	(wire
		(pts
			(xy 354.33 58.42) (xy 354.33 59.69)
		)
		(stroke
			(width 0)
			(type default)
		)
	)
	(polyline
		(pts
			(xy 215.9 265.43) (xy 215.9 271.78)
		)
		(stroke
			(width 0)
			(type dash)
		)
	)
	(wire
		(pts
			(xy 62.23 198.12) (xy 62.23 196.85)
		)
		(stroke
			(width 0)
			(type default)
		)
	)
	(wire
		(pts
			(xy 173.99 265.43) (xy 173.99 262.89)
		)
		(stroke
			(width 0)
			(type default)
		)
	)
	(wire
		(pts
			(xy 58.42 242.57) (xy 58.42 241.3)
		)
		(stroke
			(width 0)
			(type default)
		)
	)
	(wire
		(pts
			(xy 29.21 231.14) (xy 29.21 232.41)
		)
		(stroke
			(width 0)
			(type default)
		)
	)
	(wire
		(pts
			(xy 276.86 233.68) (xy 276.86 231.14)
		)
		(stroke
			(width 0)
			(type default)
		)
	)
	(wire
		(pts
			(xy 44.45 93.98) (xy 44.45 92.71)
		)
		(stroke
			(width 0)
			(type default)
		)
	)
	(wire
		(pts
			(xy 111.76 142.24) (xy 111.76 138.43)
		)
		(stroke
			(width 0)
			(type default)
		)
	)
	(wire
		(pts
			(xy 102.87 148.59) (xy 102.87 147.32)
		)
		(stroke
			(width 0)
			(type default)
		)
	)
	(wire
		(pts
			(xy 160.02 264.16) (xy 160.02 262.89)
		)
		(stroke
			(width 0)
			(type default)
		)
	)
	(wire
		(pts
			(xy 80.01 59.69) (xy 80.01 60.96)
		)
		(stroke
			(width 0)
			(type default)
		)
	)
	(wire
		(pts
			(xy 163.83 232.41) (xy 163.83 234.95)
		)
		(stroke
			(width 0)
			(type default)
		)
	)
	(polyline
		(pts
			(xy 254 232.41) (xy 267.97 232.41)
		)
		(stroke
			(width 0)
			(type dash)
		)
	)
	(wire
		(pts
			(xy 36.83 173.99) (xy 36.83 172.72)
		)
		(stroke
			(width 0)
			(type default)
		)
	)
	(polyline
		(pts
			(xy 134.62 67.31) (xy 134.62 57.15)
		)
		(stroke
			(width 0)
			(type dash)
		)
	)
	(polyline
		(pts
			(xy 267.97 232.41) (xy 267.97 240.03)
		)
		(stroke
			(width 0)
			(type dash)
		)
	)
	(wire
		(pts
			(xy 78.74 198.12) (xy 78.74 196.85)
		)
		(stroke
			(width 0)
			(type default)
		)
	)
	(wire
		(pts
			(xy 177.8 232.41) (xy 171.45 232.41)
		)
		(stroke
			(width 0)
			(type default)
		)
	)
	(wire
		(pts
			(xy 71.12 67.31) (xy 71.12 66.04)
		)
		(stroke
			(width 0)
			(type default)
		)
	)
	(wire
		(pts
			(xy 111.76 198.12) (xy 111.76 196.85)
		)
		(stroke
			(width 0)
			(type default)
		)
	)
	(wire
		(pts
			(xy 160.02 261.62) (xy 160.02 262.89)
		)
		(stroke
			(width 0)
			(type default)
		)
	)
	(polyline
		(pts
			(xy 266.7 264.16) (xy 266.7 271.78)
		)
		(stroke
			(width 0)
			(type dash)
		)
	)
	(polyline
		(pts
			(xy 346.71 125.73) (xy 346.71 134.62)
		)
		(stroke
			(width 0)
			(type dash)
		)
	)
	(wire
		(pts
			(xy 60.96 67.31) (xy 60.96 66.04)
		)
		(stroke
			(width 0)
			(type default)
		)
	)
	(wire
		(pts
			(xy 223.52 111.76) (xy 224.79 111.76)
		)
		(stroke
			(width 0)
			(type default)
		)
	)
	(wire
		(pts
			(xy 345.44 166.37) (xy 355.6 166.37)
		)
		(stroke
			(width 0)
			(type default)
		)
	)
	(wire
		(pts
			(xy 44.45 142.24) (xy 44.45 138.43)
		)
		(stroke
			(width 0)
			(type default)
		)
	)
	(wire
		(pts
			(xy 78.74 163.83) (xy 86.36 163.83)
		)
		(stroke
			(width 0)
			(type default)
		)
	)
	(wire
		(pts
			(xy 69.85 173.99) (xy 69.85 172.72)
		)
		(stroke
			(width 0)
			(type default)
		)
	)
	(symbol
		(lib_id "antmicroCapacitors0402:C_10u_10V_0402")
		(at 210.82 271.78 90)
		(unit 1)
		(exclude_from_sim no)
		(in_bom yes)
		(on_board yes)
		(dnp no)
		(property "Reference" "C95"
			(at 212.09 267.335 90)
			(effects
				(font
					(size 1.27 1.27)
					(thickness 0.15)
				)
				(justify right)
			)
		)
		(property "Value" "C_10u_10V_0402"
			(at 220.98 251.46 0)
			(effects
				(font
					(size 1.27 1.27)
					(thickness 0.15)
				)
				(justify left bottom)
				(hide yes)
			)
		)
		(property "Footprint" "antmicro-footprints:C_0402_1005Metric_EIA"
			(at 223.52 251.46 0)
			(effects
				(font
					(size 1.27 1.27)
					(thickness 0.15)
				)
				(justify left bottom)
				(hide yes)
			)
		)
		(property "Datasheet" "https://www.murata.com/products/productdetail?partno=GRM155R61A106ME11%23"
			(at 226.06 251.46 0)
			(effects
				(font
					(size 1.27 1.27)
					(thickness 0.15)
				)
				(justify left bottom)
				(hide yes)
			)
		)
		(property "Description" ""
			(at 210.82 271.78 0)
			(effects
				(font
					(size 1.27 1.27)
				)
				(hide yes)
			)
		)
		(property "MPN" "GRM155R61A106ME11D"
			(at 228.6 251.46 0)
			(effects
				(font
					(size 1.27 1.27)
					(thickness 0.15)
				)
				(justify left bottom)
				(hide yes)
			)
		)
		(property "Manufacturer" "Murata"
			(at 231.14 251.46 0)
			(effects
				(font
					(size 1.27 1.27)
					(thickness 0.15)
				)
				(justify left bottom)
				(hide yes)
			)
		)
		(property "License" "Apache-2.0"
			(at 233.68 251.46 0)
			(effects
				(font
					(size 1.27 1.27)
					(thickness 0.15)
				)
				(justify left bottom)
				(hide yes)
			)
		)
		(property "Author" "Antmicro"
			(at 236.22 251.46 0)
			(effects
				(font
					(size 1.27 1.27)
					(thickness 0.15)
				)
				(justify left bottom)
				(hide yes)
			)
		)
		(property "Val" "10u"
			(at 212.09 271.145 90)
			(effects
				(font
					(size 1.27 1.27)
					(thickness 0.15)
				)
				(justify right)
			)
		)
		(property "Voltage" "10V"
			(at 238.76 251.46 0)
			(effects
				(font
					(size 1.27 1.27)
				)
				(justify left bottom)
				(hide yes)
			)
		)
		(property "Dielectric" "X5R"
			(at 241.3 251.46 0)
			(effects
				(font
					(size 1.27 1.27)
				)
				(justify left bottom)
				(hide yes)
			)
		)
		(pin "1"
		)
		(pin "2"
		)
		(instances
			(project "data-center-rdimm-ddr5-tester"
				(path ""
					(reference "C95")
					(unit 1)
				)
			)
		)
	)
	(symbol
		(lib_id "antmicroCapacitors0402:C_10u_10V_0402")
		(at 167.64 270.51 90)
		(unit 1)
		(exclude_from_sim no)
		(in_bom yes)
		(on_board yes)
		(dnp no)
		(property "Reference" "C18"
			(at 168.91 266.065 90)
			(effects
				(font
					(size 1.27 1.27)
					(thickness 0.15)
				)
				(justify right)
			)
		)
		(property "Value" "C_10u_10V_0402"
			(at 177.8 250.19 0)
			(effects
				(font
					(size 1.27 1.27)
					(thickness 0.15)
				)
				(justify left bottom)
				(hide yes)
			)
		)
		(property "Footprint" "antmicro-footprints:C_0402_1005Metric_EIA"
			(at 180.34 250.19 0)
			(effects
				(font
					(size 1.27 1.27)
					(thickness 0.15)
				)
				(justify left bottom)
				(hide yes)
			)
		)
		(property "Datasheet" "https://www.murata.com/products/productdetail?partno=GRM155R61A106ME11%23"
			(at 182.88 250.19 0)
			(effects
				(font
					(size 1.27 1.27)
					(thickness 0.15)
				)
				(justify left bottom)
				(hide yes)
			)
		)
		(property "Description" ""
			(at 167.64 270.51 0)
			(effects
				(font
					(size 1.27 1.27)
				)
				(hide yes)
			)
		)
		(property "MPN" "GRM155R61A106ME11D"
			(at 185.42 250.19 0)
			(effects
				(font
					(size 1.27 1.27)
					(thickness 0.15)
				)
				(justify left bottom)
				(hide yes)
			)
		)
		(property "Manufacturer" "Murata"
			(at 187.96 250.19 0)
			(effects
				(font
					(size 1.27 1.27)
					(thickness 0.15)
				)
				(justify left bottom)
				(hide yes)
			)
		)
		(property "License" "Apache-2.0"
			(at 190.5 250.19 0)
			(effects
				(font
					(size 1.27 1.27)
					(thickness 0.15)
				)
				(justify left bottom)
				(hide yes)
			)
		)
		(property "Author" "Antmicro"
			(at 193.04 250.19 0)
			(effects
				(font
					(size 1.27 1.27)
					(thickness 0.15)
				)
				(justify left bottom)
				(hide yes)
			)
		)
		(property "Val" "10u"
			(at 168.91 269.875 90)
			(effects
				(font
					(size 1.27 1.27)
					(thickness 0.15)
				)
				(justify right)
			)
		)
		(property "Voltage" "10V"
			(at 195.58 250.19 0)
			(effects
				(font
					(size 1.27 1.27)
				)
				(justify left bottom)
				(hide yes)
			)
		)
		(property "Dielectric" "X5R"
			(at 198.12 250.19 0)
			(effects
				(font
					(size 1.27 1.27)
				)
				(justify left bottom)
				(hide yes)
			)
		)
		(pin "1"
		)
		(pin "2"
		)
		(instances
			(project "data-center-rdimm-ddr5-tester"
				(path ""
					(reference "C18")
					(unit 1)
				)
			)
		)
	)
	(symbol
		(lib_id "antmicropower:GND")
		(at 160.02 271.78 0)
		(unit 1)
		(exclude_from_sim no)
		(in_bom yes)
		(on_board yes)
		(dnp no)
		(fields_autoplaced yes)
		(property "Reference" "#PWR0122"
			(at 160.02 278.13 0)
			(effects
				(font
					(size 1.27 1.27)
				)
				(hide yes)
			)
		)
		(property "Value" "GND"
			(at 158.115 276.225 0)
			(effects
				(font
					(size 1.27 1.27)
					(thickness 0.15)
				)
				(justify left bottom)
			)
		)
		(property "Footprint" ""
			(at 168.91 279.4 0)
			(effects
				(font
					(size 1.27 1.27)
					(thickness 0.15)
				)
				(justify left bottom)
				(hide yes)
			)
		)
		(property "Datasheet" ""
			(at 168.91 284.48 0)
			(effects
				(font
					(size 1.27 1.27)
					(thickness 0.15)
				)
				(justify left bottom)
				(hide yes)
			)
		)
		(property "Description" ""
			(at 160.02 271.78 0)
			(effects
				(font
					(size 1.27 1.27)
				)
				(hide yes)
			)
		)
		(property "Author" "Antmicro"
			(at 168.91 276.86 0)
			(effects
				(font
					(size 1.27 1.27)
					(thickness 0.15)
				)
				(justify left bottom)
				(hide yes)
			)
		)
		(property "License" "Apache-2.0"
			(at 168.91 279.4 0)
			(effects
				(font
					(size 1.27 1.27)
					(thickness 0.15)
				)
				(justify left bottom)
				(hide yes)
			)
		)
		(pin "1"
		)
		(instances
			(project "data-center-rdimm-ddr5-tester"
				(path ""
					(reference "#PWR0122")
					(unit 1)
				)
			)
		)
	)
	(symbol
		(lib_id "antmicropower:GND")
		(at 127 67.31 0)
		(mirror y)
		(unit 1)
		(exclude_from_sim no)
		(in_bom yes)
		(on_board yes)
		(dnp no)
		(fields_autoplaced yes)
		(property "Reference" "#PWR0150"
			(at 127 73.66 0)
			(effects
				(font
					(size 1.27 1.27)
				)
				(hide yes)
			)
		)
		(property "Value" "GND"
			(at 128.905 71.755 0)
			(effects
				(font
					(size 1.27 1.27)
					(thickness 0.15)
				)
				(justify left bottom)
			)
		)
		(property "Footprint" ""
			(at 118.11 74.93 0)
			(effects
				(font
					(size 1.27 1.27)
					(thickness 0.15)
				)
				(justify left bottom)
				(hide yes)
			)
		)
		(property "Datasheet" ""
			(at 118.11 80.01 0)
			(effects
				(font
					(size 1.27 1.27)
					(thickness 0.15)
				)
				(justify left bottom)
				(hide yes)
			)
		)
		(property "Description" ""
			(at 127 67.31 0)
			(effects
				(font
					(size 1.27 1.27)
				)
				(hide yes)
			)
		)
		(property "Author" "Antmicro"
			(at 118.11 72.39 0)
			(effects
				(font
					(size 1.27 1.27)
					(thickness 0.15)
				)
				(justify left bottom)
				(hide yes)
			)
		)
		(property "License" "Apache-2.0"
			(at 118.11 74.93 0)
			(effects
				(font
					(size 1.27 1.27)
					(thickness 0.15)
				)
				(justify left bottom)
				(hide yes)
			)
		)
		(pin "1"
		)
		(instances
			(project "data-center-rdimm-ddr5-tester"
				(path ""
					(reference "#PWR0150")
					(unit 1)
				)
			)
		)
	)
	(symbol
		(lib_id "antmicropower:GND")
		(at 69.85 120.65 0)
		(unit 1)
		(exclude_from_sim no)
		(in_bom yes)
		(on_board yes)
		(dnp no)
		(fields_autoplaced yes)
		(property "Reference" "#PWR089"
			(at 69.85 127 0)
			(effects
				(font
					(size 1.27 1.27)
				)
				(hide yes)
			)
		)
		(property "Value" "GND"
			(at 67.945 125.095 0)
			(effects
				(font
					(size 1.27 1.27)
					(thickness 0.15)
				)
				(justify left bottom)
			)
		)
		(property "Footprint" ""
			(at 78.74 128.27 0)
			(effects
				(font
					(size 1.27 1.27)
					(thickness 0.15)
				)
				(justify left bottom)
				(hide yes)
			)
		)
		(property "Datasheet" ""
			(at 78.74 133.35 0)
			(effects
				(font
					(size 1.27 1.27)
					(thickness 0.15)
				)
				(justify left bottom)
				(hide yes)
			)
		)
		(property "Description" ""
			(at 69.85 120.65 0)
			(effects
				(font
					(size 1.27 1.27)
				)
				(hide yes)
			)
		)
		(property "Author" "Antmicro"
			(at 78.74 125.73 0)
			(effects
				(font
					(size 1.27 1.27)
					(thickness 0.15)
				)
				(justify left bottom)
				(hide yes)
			)
		)
		(property "License" "Apache-2.0"
			(at 78.74 128.27 0)
			(effects
				(font
					(size 1.27 1.27)
					(thickness 0.15)
				)
				(justify left bottom)
				(hide yes)
			)
		)
		(pin "1"
		)
		(instances
			(project "data-center-rdimm-ddr5-tester"
				(path ""
					(reference "#PWR089")
					(unit 1)
				)
			)
		)
	)
	(symbol
		(lib_id "antmicroCapacitors0402:C_100n_0402")
		(at 349.25 133.35 90)
		(unit 1)
		(exclude_from_sim no)
		(in_bom yes)
		(on_board yes)
		(dnp no)
		(property "Reference" "C98"
			(at 349.885 128.905 90)
			(effects
				(font
					(size 1.27 1.27)
					(thickness 0.15)
				)
				(justify right)
			)
		)
		(property "Value" "C_100n_0402"
			(at 359.41 113.03 0)
			(effects
				(font
					(size 1.27 1.27)
					(thickness 0.15)
				)
				(justify left bottom)
				(hide yes)
			)
		)
		(property "Footprint" "antmicro-footprints:C_0402_1005Metric_EIA"
			(at 361.95 113.03 0)
			(effects
				(font
					(size 1.27 1.27)
					(thickness 0.15)
				)
				(justify left bottom)
				(hide yes)
			)
		)
		(property "Datasheet" "https://www.murata.com/products/productdetail?partno=GRM155R61H104KE14%23"
			(at 364.49 113.03 0)
			(effects
				(font
					(size 1.27 1.27)
					(thickness 0.15)
				)
				(justify left bottom)
				(hide yes)
			)
		)
		(property "Description" ""
			(at 349.25 133.35 0)
			(effects
				(font
					(size 1.27 1.27)
				)
				(hide yes)
			)
		)
		(property "MPN" "GRM155R61H104KE14D"
			(at 367.03 113.03 0)
			(effects
				(font
					(size 1.27 1.27)
					(thickness 0.15)
				)
				(justify left bottom)
				(hide yes)
			)
		)
		(property "Manufacturer" "Murata"
			(at 369.57 113.03 0)
			(effects
				(font
					(size 1.27 1.27)
					(thickness 0.15)
				)
				(justify left bottom)
				(hide yes)
			)
		)
		(property "License" "Apache-2.0"
			(at 372.11 113.03 0)
			(effects
				(font
					(size 1.27 1.27)
					(thickness 0.15)
				)
				(justify left bottom)
				(hide yes)
			)
		)
		(property "Author" "Antmicro"
			(at 374.65 113.03 0)
			(effects
				(font
					(size 1.27 1.27)
					(thickness 0.15)
				)
				(justify left bottom)
				(hide yes)
			)
		)
		(property "Val" "100n"
			(at 349.885 132.715 90)
			(effects
				(font
					(size 1.27 1.27)
					(thickness 0.15)
				)
				(justify right)
			)
		)
		(property "Voltage" "50V"
			(at 377.19 113.03 0)
			(effects
				(font
					(size 1.27 1.27)
				)
				(justify left bottom)
				(hide yes)
			)
		)
		(property "Dielectric" "X5R"
			(at 379.73 113.03 0)
			(effects
				(font
					(size 1.27 1.27)
				)
				(justify left bottom)
				(hide yes)
			)
		)
		(pin "1"
		)
		(pin "2"
		)
		(instances
			(project "data-center-rdimm-ddr5-tester"
				(path ""
					(reference "C98")
					(unit 1)
				)
			)
		)
	)
	(symbol
		(lib_id "antmicroCapacitors0402:C_100n_0402")
		(at 238.76 240.03 90)
		(unit 1)
		(exclude_from_sim no)
		(in_bom yes)
		(on_board yes)
		(dnp no)
		(property "Reference" "C78"
			(at 239.395 235.585 90)
			(effects
				(font
					(size 1.27 1.27)
					(thickness 0.15)
				)
				(justify right)
			)
		)
		(property "Value" "C_100n_0402"
			(at 248.92 219.71 0)
			(effects
				(font
					(size 1.27 1.27)
					(thickness 0.15)
				)
				(justify left bottom)
				(hide yes)
			)
		)
		(property "Footprint" "antmicro-footprints:C_0402_1005Metric_EIA"
			(at 251.46 219.71 0)
			(effects
				(font
					(size 1.27 1.27)
					(thickness 0.15)
				)
				(justify left bottom)
				(hide yes)
			)
		)
		(property "Datasheet" "https://www.murata.com/products/productdetail?partno=GRM155R61H104KE14%23"
			(at 254 219.71 0)
			(effects
				(font
					(size 1.27 1.27)
					(thickness 0.15)
				)
				(justify left bottom)
				(hide yes)
			)
		)
		(property "Description" ""
			(at 238.76 240.03 0)
			(effects
				(font
					(size 1.27 1.27)
				)
				(hide yes)
			)
		)
		(property "MPN" "GRM155R61H104KE14D"
			(at 256.54 219.71 0)
			(effects
				(font
					(size 1.27 1.27)
					(thickness 0.15)
				)
				(justify left bottom)
				(hide yes)
			)
		)
		(property "Manufacturer" "Murata"
			(at 259.08 219.71 0)
			(effects
				(font
					(size 1.27 1.27)
					(thickness 0.15)
				)
				(justify left bottom)
				(hide yes)
			)
		)
		(property "License" "Apache-2.0"
			(at 261.62 219.71 0)
			(effects
				(font
					(size 1.27 1.27)
					(thickness 0.15)
				)
				(justify left bottom)
				(hide yes)
			)
		)
		(property "Author" "Antmicro"
			(at 264.16 219.71 0)
			(effects
				(font
					(size 1.27 1.27)
					(thickness 0.15)
				)
				(justify left bottom)
				(hide yes)
			)
		)
		(property "Val" "100n"
			(at 239.395 239.395 90)
			(effects
				(font
					(size 1.27 1.27)
					(thickness 0.15)
				)
				(justify right)
			)
		)
		(property "Voltage" "50V"
			(at 266.7 219.71 0)
			(effects
				(font
					(size 1.27 1.27)
				)
				(justify left bottom)
				(hide yes)
			)
		)
		(property "Dielectric" "X5R"
			(at 269.24 219.71 0)
			(effects
				(font
					(size 1.27 1.27)
				)
				(justify left bottom)
				(hide yes)
			)
		)
		(pin "1"
		)
		(pin "2"
		)
		(instances
			(project "data-center-rdimm-ddr5-tester"
				(path ""
					(reference "C78")
					(unit 1)
				)
			)
		)
	)
	(symbol
		(lib_id "antmicroCapacitors0402:C_1u_25V_0402")
		(at 44.45 172.72 90)
		(unit 1)
		(exclude_from_sim no)
		(in_bom yes)
		(on_board yes)
		(dnp no)
		(fields_autoplaced yes)
		(property "Reference" "C51"
			(at 46.99 168.9036 90)
			(effects
				(font
					(size 1.27 1.27)
					(thickness 0.15)
				)
				(justify right)
			)
		)
		(property "Value" "C_1u_25V_0402"
			(at 54.61 152.4 0)
			(effects
				(font
					(size 1.27 1.27)
					(thickness 0.15)
				)
				(justify left bottom)
				(hide yes)
			)
		)
		(property "Footprint" "antmicro-footprints:C_0402_1005Metric_EIA"
			(at 57.15 152.4 0)
			(effects
				(font
					(size 1.27 1.27)
					(thickness 0.15)
				)
				(justify left bottom)
				(hide yes)
			)
		)
		(property "Datasheet" "https://www.murata.com/products/productdetail?partno=GRM155R61E105KE11%23"
			(at 59.69 152.4 0)
			(effects
				(font
					(size 1.27 1.27)
					(thickness 0.15)
				)
				(justify left bottom)
				(hide yes)
			)
		)
		(property "Description" ""
			(at 44.45 172.72 0)
			(effects
				(font
					(size 1.27 1.27)
				)
				(hide yes)
			)
		)
		(property "MPN" "GRM155R61E105KE11J"
			(at 62.23 152.4 0)
			(effects
				(font
					(size 1.27 1.27)
					(thickness 0.15)
				)
				(justify left bottom)
				(hide yes)
			)
		)
		(property "Manufacturer" "Murata"
			(at 64.77 152.4 0)
			(effects
				(font
					(size 1.27 1.27)
					(thickness 0.15)
				)
				(justify left bottom)
				(hide yes)
			)
		)
		(property "License" "Apache-2.0"
			(at 67.31 152.4 0)
			(effects
				(font
					(size 1.27 1.27)
					(thickness 0.15)
				)
				(justify left bottom)
				(hide yes)
			)
		)
		(property "Author" "Antmicro"
			(at 69.85 152.4 0)
			(effects
				(font
					(size 1.27 1.27)
					(thickness 0.15)
				)
				(justify left bottom)
				(hide yes)
			)
		)
		(property "Val" "1u"
			(at 46.99 171.4436 90)
			(effects
				(font
					(size 1.27 1.27)
					(thickness 0.15)
				)
				(justify right)
			)
		)
		(property "Voltage" "25V"
			(at 72.39 152.4 0)
			(effects
				(font
					(size 1.27 1.27)
				)
				(justify left bottom)
				(hide yes)
			)
		)
		(property "Dielectric" "X5R"
			(at 74.93 152.4 0)
			(effects
				(font
					(size 1.27 1.27)
				)
				(justify left bottom)
				(hide yes)
			)
		)
		(pin "1"
		)
		(pin "2"
		)
		(instances
			(project "data-center-rdimm-ddr5-tester"
				(path ""
					(reference "C51")
					(unit 1)
				)
			)
		)
	)
	(symbol
		(lib_id "antmicroCapacitors0402:C_1u_25V_0402")
		(at 111.76 172.72 90)
		(unit 1)
		(exclude_from_sim no)
		(in_bom yes)
		(on_board yes)
		(dnp no)
		(fields_autoplaced yes)
		(property "Reference" "C79"
			(at 114.3 168.9036 90)
			(effects
				(font
					(size 1.27 1.27)
					(thickness 0.15)
				)
				(justify right)
			)
		)
		(property "Value" "C_1u_25V_0402"
			(at 121.92 152.4 0)
			(effects
				(font
					(size 1.27 1.27)
					(thickness 0.15)
				)
				(justify left bottom)
				(hide yes)
			)
		)
		(property "Footprint" "antmicro-footprints:C_0402_1005Metric_EIA"
			(at 124.46 152.4 0)
			(effects
				(font
					(size 1.27 1.27)
					(thickness 0.15)
				)
				(justify left bottom)
				(hide yes)
			)
		)
		(property "Datasheet" "https://www.murata.com/products/productdetail?partno=GRM155R61E105KE11%23"
			(at 127 152.4 0)
			(effects
				(font
					(size 1.27 1.27)
					(thickness 0.15)
				)
				(justify left bottom)
				(hide yes)
			)
		)
		(property "Description" ""
			(at 111.76 172.72 0)
			(effects
				(font
					(size 1.27 1.27)
				)
				(hide yes)
			)
		)
		(property "MPN" "GRM155R61E105KE11J"
			(at 129.54 152.4 0)
			(effects
				(font
					(size 1.27 1.27)
					(thickness 0.15)
				)
				(justify left bottom)
				(hide yes)
			)
		)
		(property "Manufacturer" "Murata"
			(at 132.08 152.4 0)
			(effects
				(font
					(size 1.27 1.27)
					(thickness 0.15)
				)
				(justify left bottom)
				(hide yes)
			)
		)
		(property "License" "Apache-2.0"
			(at 134.62 152.4 0)
			(effects
				(font
					(size 1.27 1.27)
					(thickness 0.15)
				)
				(justify left bottom)
				(hide yes)
			)
		)
		(property "Author" "Antmicro"
			(at 137.16 152.4 0)
			(effects
				(font
					(size 1.27 1.27)
					(thickness 0.15)
				)
				(justify left bottom)
				(hide yes)
			)
		)
		(property "Val" "1u"
			(at 114.3 171.4436 90)
			(effects
				(font
					(size 1.27 1.27)
					(thickness 0.15)
				)
				(justify right)
			)
		)
		(property "Voltage" "25V"
			(at 139.7 152.4 0)
			(effects
				(font
					(size 1.27 1.27)
				)
				(justify left bottom)
				(hide yes)
			)
		)
		(property "Dielectric" "X5R"
			(at 142.24 152.4 0)
			(effects
				(font
					(size 1.27 1.27)
				)
				(justify left bottom)
				(hide yes)
			)
		)
		(pin "1"
		)
		(pin "2"
		)
		(instances
			(project "data-center-rdimm-ddr5-tester"
				(path ""
					(reference "C79")
					(unit 1)
				)
			)
		)
	)
	(symbol
		(lib_id "antmicroCapacitors0402:C_1u_25V_0402")
		(at 111.76 147.32 90)
		(unit 1)
		(exclude_from_sim no)
		(in_bom yes)
		(on_board yes)
		(dnp no)
		(fields_autoplaced yes)
		(property "Reference" "C47"
			(at 114.3 143.5036 90)
			(effects
				(font
					(size 1.27 1.27)
					(thickness 0.15)
				)
				(justify right)
			)
		)
		(property "Value" "C_1u_25V_0402"
			(at 121.92 127 0)
			(effects
				(font
					(size 1.27 1.27)
					(thickness 0.15)
				)
				(justify left bottom)
				(hide yes)
			)
		)
		(property "Footprint" "antmicro-footprints:C_0402_1005Metric_EIA"
			(at 124.46 127 0)
			(effects
				(font
					(size 1.27 1.27)
					(thickness 0.15)
				)
				(justify left bottom)
				(hide yes)
			)
		)
		(property "Datasheet" "https://www.murata.com/products/productdetail?partno=GRM155R61E105KE11%23"
			(at 127 127 0)
			(effects
				(font
					(size 1.27 1.27)
					(thickness 0.15)
				)
				(justify left bottom)
				(hide yes)
			)
		)
		(property "Description" ""
			(at 111.76 147.32 0)
			(effects
				(font
					(size 1.27 1.27)
				)
				(hide yes)
			)
		)
		(property "MPN" "GRM155R61E105KE11J"
			(at 129.54 127 0)
			(effects
				(font
					(size 1.27 1.27)
					(thickness 0.15)
				)
				(justify left bottom)
				(hide yes)
			)
		)
		(property "Manufacturer" "Murata"
			(at 132.08 127 0)
			(effects
				(font
					(size 1.27 1.27)
					(thickness 0.15)
				)
				(justify left bottom)
				(hide yes)
			)
		)
		(property "License" "Apache-2.0"
			(at 134.62 127 0)
			(effects
				(font
					(size 1.27 1.27)
					(thickness 0.15)
				)
				(justify left bottom)
				(hide yes)
			)
		)
		(property "Author" "Antmicro"
			(at 137.16 127 0)
			(effects
				(font
					(size 1.27 1.27)
					(thickness 0.15)
				)
				(justify left bottom)
				(hide yes)
			)
		)
		(property "Val" "1u"
			(at 114.3 146.0436 90)
			(effects
				(font
					(size 1.27 1.27)
					(thickness 0.15)
				)
				(justify right)
			)
		)
		(property "Voltage" "25V"
			(at 139.7 127 0)
			(effects
				(font
					(size 1.27 1.27)
				)
				(justify left bottom)
				(hide yes)
			)
		)
		(property "Dielectric" "X5R"
			(at 142.24 127 0)
			(effects
				(font
					(size 1.27 1.27)
				)
				(justify left bottom)
				(hide yes)
			)
		)
		(pin "1"
		)
		(pin "2"
		)
		(instances
			(project "data-center-rdimm-ddr5-tester"
				(path ""
					(reference "C47")
					(unit 1)
				)
			)
		)
	)
	(symbol
		(lib_id "antmicropower:GND")
		(at 368.3 66.04 0)
		(unit 1)
		(exclude_from_sim no)
		(in_bom yes)
		(on_board yes)
		(dnp no)
		(fields_autoplaced yes)
		(property "Reference" "#PWR0167"
			(at 368.3 72.39 0)
			(effects
				(font
					(size 1.27 1.27)
				)
				(hide yes)
			)
		)
		(property "Value" "GND"
			(at 366.395 70.485 0)
			(effects
				(font
					(size 1.27 1.27)
					(thickness 0.15)
				)
				(justify left bottom)
			)
		)
		(property "Footprint" ""
			(at 377.19 73.66 0)
			(effects
				(font
					(size 1.27 1.27)
					(thickness 0.15)
				)
				(justify left bottom)
				(hide yes)
			)
		)
		(property "Datasheet" ""
			(at 377.19 78.74 0)
			(effects
				(font
					(size 1.27 1.27)
					(thickness 0.15)
				)
				(justify left bottom)
				(hide yes)
			)
		)
		(property "Description" ""
			(at 368.3 66.04 0)
			(effects
				(font
					(size 1.27 1.27)
				)
				(hide yes)
			)
		)
		(property "Author" "Antmicro"
			(at 377.19 71.12 0)
			(effects
				(font
					(size 1.27 1.27)
					(thickness 0.15)
				)
				(justify left bottom)
				(hide yes)
			)
		)
		(property "License" "Apache-2.0"
			(at 377.19 73.66 0)
			(effects
				(font
					(size 1.27 1.27)
					(thickness 0.15)
				)
				(justify left bottom)
				(hide yes)
			)
		)
		(pin "1"
		)
		(instances
			(project "data-center-rdimm-ddr5-tester"
				(path ""
					(reference "#PWR0167")
					(unit 1)
				)
			)
		)
	)
	(symbol
		(lib_id "antmicropower:GND")
		(at 210.82 273.05 0)
		(unit 1)
		(exclude_from_sim no)
		(in_bom yes)
		(on_board yes)
		(dnp no)
		(fields_autoplaced yes)
		(property "Reference" "#PWR0164"
			(at 210.82 279.4 0)
			(effects
				(font
					(size 1.27 1.27)
				)
				(hide yes)
			)
		)
		(property "Value" "GND"
			(at 208.915 277.495 0)
			(effects
				(font
					(size 1.27 1.27)
					(thickness 0.15)
				)
				(justify left bottom)
			)
		)
		(property "Footprint" ""
			(at 219.71 280.67 0)
			(effects
				(font
					(size 1.27 1.27)
					(thickness 0.15)
				)
				(justify left bottom)
				(hide yes)
			)
		)
		(property "Datasheet" ""
			(at 219.71 285.75 0)
			(effects
				(font
					(size 1.27 1.27)
					(thickness 0.15)
				)
				(justify left bottom)
				(hide yes)
			)
		)
		(property "Description" ""
			(at 210.82 273.05 0)
			(effects
				(font
					(size 1.27 1.27)
				)
				(hide yes)
			)
		)
		(property "Author" "Antmicro"
			(at 219.71 278.13 0)
			(effects
				(font
					(size 1.27 1.27)
					(thickness 0.15)
				)
				(justify left bottom)
				(hide yes)
			)
		)
		(property "License" "Apache-2.0"
			(at 219.71 280.67 0)
			(effects
				(font
					(size 1.27 1.27)
					(thickness 0.15)
				)
				(justify left bottom)
				(hide yes)
			)
		)
		(pin "1"
		)
		(instances
			(project "data-center-rdimm-ddr5-tester"
				(path ""
					(reference "#PWR0164")
					(unit 1)
				)
			)
		)
	)
	(symbol
		(lib_id "antmicroCapacitorspol:C_Pol_1m_2.5V_KEMET-T520-D")
		(at 27.94 60.96 270)
		(unit 1)
		(exclude_from_sim no)
		(in_bom yes)
		(on_board yes)
		(dnp no)
		(fields_autoplaced yes)
		(property "Reference" "C66"
			(at 30.353 62.136 90)
			(effects
				(font
					(size 1.27 1.27)
					(thickness 0.15)
				)
				(justify left)
			)
		)
		(property "Value" "C_Pol_1m_2.5V_KEMET-T520-D"
			(at 25.4 74.93 0)
			(effects
				(font
					(size 1.27 1.27)
					(thickness 0.15)
				)
				(justify left bottom)
				(hide yes)
			)
		)
		(property "Footprint" "antmicro-footprints:C_Pol_EIA-D"
			(at 20.32 74.93 0)
			(effects
				(font
					(size 1.27 1.27)
					(thickness 0.15)
				)
				(justify left bottom)
				(hide yes)
			)
		)
		(property "Datasheet" "https://www.kemet.com/en/us/capacitors/product/T520D108M2R5ATE030.html"
			(at 17.78 74.93 0)
			(effects
				(font
					(size 1.27 1.27)
					(thickness 0.15)
				)
				(justify left bottom)
				(hide yes)
			)
		)
		(property "Description" ""
			(at 27.94 60.96 0)
			(effects
				(font
					(size 1.27 1.27)
				)
				(hide yes)
			)
		)
		(property "MPN" "T520D108M2R5ATE030"
			(at 15.24 74.93 0)
			(effects
				(font
					(size 1.27 1.27)
					(thickness 0.15)
				)
				(justify left bottom)
				(hide yes)
			)
		)
		(property "Manufacturer" "KEMET"
			(at 12.7 74.93 0)
			(effects
				(font
					(size 1.27 1.27)
					(thickness 0.15)
				)
				(justify left bottom)
				(hide yes)
			)
		)
		(property "License" "Apache-2.0"
			(at 10.16 74.93 0)
			(effects
				(font
					(size 1.27 1.27)
					(thickness 0.15)
				)
				(justify left bottom)
				(hide yes)
			)
		)
		(property "Author" "Antmicro"
			(at 7.62 74.93 0)
			(effects
				(font
					(size 1.27 1.27)
					(thickness 0.15)
				)
				(justify left bottom)
				(hide yes)
			)
		)
		(property "Val" "1000u"
			(at 30.353 64.6597 90)
			(effects
				(font
					(size 1.27 1.27)
					(thickness 0.15)
				)
				(justify left)
			)
		)
		(property "Voltage" "2.5V"
			(at 5.08 74.93 0)
			(effects
				(font
					(size 1.27 1.27)
				)
				(justify left bottom)
				(hide yes)
			)
		)
		(property "Dielectric" "template_dielectric"
			(at 2.54 74.93 0)
			(effects
				(font
					(size 1.27 1.27)
				)
				(justify left bottom)
				(hide yes)
			)
		)
		(pin "1"
		)
		(pin "2"
		)
		(instances
			(project "data-center-rdimm-ddr5-tester"
				(path ""
					(reference "C66")
					(unit 1)
				)
			)
		)
	)
	(symbol
		(lib_id "antmicroCapacitors0603:C_47u_0603")
		(at 160.02 264.16 270)
		(unit 1)
		(exclude_from_sim no)
		(in_bom yes)
		(on_board yes)
		(dnp no)
		(property "Reference" "C73"
			(at 160.655 264.795 90)
			(effects
				(font
					(size 1.27 1.27)
				)
				(justify left)
			)
		)
		(property "Value" "C_47u_0603"
			(at 149.86 284.48 0)
			(effects
				(font
					(size 1.27 1.27)
					(thickness 0.15)
				)
				(justify left bottom)
				(hide yes)
			)
		)
		(property "Footprint" "antmicro-footprints:C_0603_1608Metric"
			(at 147.32 284.48 0)
			(effects
				(font
					(size 1.27 1.27)
					(thickness 0.15)
				)
				(justify left bottom)
				(hide yes)
			)
		)
		(property "Datasheet" "https://www.murata.com/products/productdetail?partno=GRM188R60J476ME15%23"
			(at 144.78 284.48 0)
			(effects
				(font
					(size 1.27 1.27)
					(thickness 0.15)
				)
				(justify left bottom)
				(hide yes)
			)
		)
		(property "Description" ""
			(at 160.02 264.16 0)
			(effects
				(font
					(size 1.27 1.27)
				)
				(hide yes)
			)
		)
		(property "Manufacturer" "Murata"
			(at 139.7 284.48 0)
			(effects
				(font
					(size 1.27 1.27)
					(thickness 0.15)
				)
				(justify left bottom)
				(hide yes)
			)
		)
		(property "MPN" "GRM188R60J476ME15D"
			(at 142.24 284.48 0)
			(effects
				(font
					(size 1.27 1.27)
					(thickness 0.15)
				)
				(justify left bottom)
				(hide yes)
			)
		)
		(property "Val" "47u"
			(at 160.02 268.605 90)
			(effects
				(font
					(size 1.27 1.27)
					(thickness 0.15)
				)
				(justify left)
			)
		)
		(property "License" "Apache-2.0"
			(at 137.16 284.48 0)
			(effects
				(font
					(size 1.27 1.27)
					(thickness 0.15)
				)
				(justify left bottom)
				(hide yes)
			)
		)
		(property "Author" "Antmicro"
			(at 134.62 284.48 0)
			(effects
				(font
					(size 1.27 1.27)
					(thickness 0.15)
				)
				(justify left bottom)
				(hide yes)
			)
		)
		(property "Voltage" ""
			(at 132.08 284.48 0)
			(effects
				(font
					(size 1.27 1.27)
				)
				(justify left bottom)
				(hide yes)
			)
		)
		(property "Dielectric" ""
			(at 129.54 284.48 0)
			(effects
				(font
					(size 1.27 1.27)
				)
				(justify left bottom)
				(hide yes)
			)
		)
		(pin "1"
		)
		(pin "2"
		)
		(instances
			(project "data-center-rdimm-ddr5-tester"
				(path ""
					(reference "C73")
					(unit 1)
				)
			)
		)
	)
	(symbol
		(lib_id "antmicroCapacitors0402:C_1u_25V_0402")
		(at 36.83 147.32 90)
		(unit 1)
		(exclude_from_sim no)
		(in_bom yes)
		(on_board yes)
		(dnp no)
		(fields_autoplaced yes)
		(property "Reference" "C34"
			(at 39.37 143.5036 90)
			(effects
				(font
					(size 1.27 1.27)
					(thickness 0.15)
				)
				(justify right)
			)
		)
		(property "Value" "C_1u_25V_0402"
			(at 46.99 127 0)
			(effects
				(font
					(size 1.27 1.27)
					(thickness 0.15)
				)
				(justify left bottom)
				(hide yes)
			)
		)
		(property "Footprint" "antmicro-footprints:C_0402_1005Metric_EIA"
			(at 49.53 127 0)
			(effects
				(font
					(size 1.27 1.27)
					(thickness 0.15)
				)
				(justify left bottom)
				(hide yes)
			)
		)
		(property "Datasheet" "https://www.murata.com/products/productdetail?partno=GRM155R61E105KE11%23"
			(at 52.07 127 0)
			(effects
				(font
					(size 1.27 1.27)
					(thickness 0.15)
				)
				(justify left bottom)
				(hide yes)
			)
		)
		(property "Description" ""
			(at 36.83 147.32 0)
			(effects
				(font
					(size 1.27 1.27)
				)
				(hide yes)
			)
		)
		(property "MPN" "GRM155R61E105KE11J"
			(at 54.61 127 0)
			(effects
				(font
					(size 1.27 1.27)
					(thickness 0.15)
				)
				(justify left bottom)
				(hide yes)
			)
		)
		(property "Manufacturer" "Murata"
			(at 57.15 127 0)
			(effects
				(font
					(size 1.27 1.27)
					(thickness 0.15)
				)
				(justify left bottom)
				(hide yes)
			)
		)
		(property "License" "Apache-2.0"
			(at 59.69 127 0)
			(effects
				(font
					(size 1.27 1.27)
					(thickness 0.15)
				)
				(justify left bottom)
				(hide yes)
			)
		)
		(property "Author" "Antmicro"
			(at 62.23 127 0)
			(effects
				(font
					(size 1.27 1.27)
					(thickness 0.15)
				)
				(justify left bottom)
				(hide yes)
			)
		)
		(property "Val" "1u"
			(at 39.37 146.0436 90)
			(effects
				(font
					(size 1.27 1.27)
					(thickness 0.15)
				)
				(justify right)
			)
		)
		(property "Voltage" "25V"
			(at 64.77 127 0)
			(effects
				(font
					(size 1.27 1.27)
				)
				(justify left bottom)
				(hide yes)
			)
		)
		(property "Dielectric" "X5R"
			(at 67.31 127 0)
			(effects
				(font
					(size 1.27 1.27)
				)
				(justify left bottom)
				(hide yes)
			)
		)
		(pin "1"
		)
		(pin "2"
		)
		(instances
			(project "data-center-rdimm-ddr5-tester"
				(path ""
					(reference "C34")
					(unit 1)
				)
			)
		)
	)
	(symbol
		(lib_id "antmicropower:GND")
		(at 346.71 101.6 0)
		(unit 1)
		(exclude_from_sim no)
		(in_bom yes)
		(on_board yes)
		(dnp no)
		(fields_autoplaced yes)
		(property "Reference" "#PWR0132"
			(at 346.71 107.95 0)
			(effects
				(font
					(size 1.27 1.27)
				)
				(hide yes)
			)
		)
		(property "Value" "GND"
			(at 344.805 106.045 0)
			(effects
				(font
					(size 1.27 1.27)
					(thickness 0.15)
				)
				(justify left bottom)
			)
		)
		(property "Footprint" ""
			(at 355.6 109.22 0)
			(effects
				(font
					(size 1.27 1.27)
					(thickness 0.15)
				)
				(justify left bottom)
				(hide yes)
			)
		)
		(property "Datasheet" ""
			(at 355.6 114.3 0)
			(effects
				(font
					(size 1.27 1.27)
					(thickness 0.15)
				)
				(justify left bottom)
				(hide yes)
			)
		)
		(property "Description" ""
			(at 346.71 101.6 0)
			(effects
				(font
					(size 1.27 1.27)
				)
				(hide yes)
			)
		)
		(property "Author" "Antmicro"
			(at 355.6 106.68 0)
			(effects
				(font
					(size 1.27 1.27)
					(thickness 0.15)
				)
				(justify left bottom)
				(hide yes)
			)
		)
		(property "License" "Apache-2.0"
			(at 355.6 109.22 0)
			(effects
				(font
					(size 1.27 1.27)
					(thickness 0.15)
				)
				(justify left bottom)
				(hide yes)
			)
		)
		(pin "1"
		)
		(instances
			(project "data-center-rdimm-ddr5-tester"
				(path ""
					(reference "#PWR0132")
					(unit 1)
				)
			)
		)
	)
	(symbol
		(lib_id "antmicropower:+0V85")
		(at 36.83 83.82 0)
		(unit 1)
		(exclude_from_sim no)
		(in_bom yes)
		(on_board yes)
		(dnp no)
		(fields_autoplaced yes)
		(property "Reference" "#PWR055"
			(at 36.83 87.63 0)
			(effects
				(font
					(size 1.27 1.27)
				)
				(hide yes)
			)
		)
		(property "Value" "+0V85"
			(at 36.83 78.74 0)
			(effects
				(font
					(size 1.27 1.27)
				)
			)
		)
		(property "Footprint" ""
			(at 36.83 83.82 0)
			(effects
				(font
					(size 1.27 1.27)
				)
				(hide yes)
			)
		)
		(property "Datasheet" ""
			(at 36.83 83.82 0)
			(effects
				(font
					(size 1.27 1.27)
				)
				(hide yes)
			)
		)
		(property "Description" ""
			(at 36.83 83.82 0)
			(effects
				(font
					(size 1.27 1.27)
				)
				(hide yes)
			)
		)
		(pin "1"
		)
		(instances
			(project "data-center-rdimm-ddr5-tester"
				(path ""
					(reference "#PWR055")
					(unit 1)
				)
			)
		)
	)
	(symbol
		(lib_id "antmicroCapacitors0603:C_47u_0603")
		(at 36.83 87.63 270)
		(unit 1)
		(exclude_from_sim no)
		(in_bom yes)
		(on_board yes)
		(dnp no)
		(property "Reference" "C62"
			(at 37.465 88.265 90)
			(effects
				(font
					(size 1.27 1.27)
				)
				(justify left)
			)
		)
		(property "Value" "C_47u_0603"
			(at 26.67 107.95 0)
			(effects
				(font
					(size 1.27 1.27)
					(thickness 0.15)
				)
				(justify left bottom)
				(hide yes)
			)
		)
		(property "Footprint" "antmicro-footprints:C_0603_1608Metric"
			(at 24.13 107.95 0)
			(effects
				(font
					(size 1.27 1.27)
					(thickness 0.15)
				)
				(justify left bottom)
				(hide yes)
			)
		)
		(property "Datasheet" "https://www.murata.com/products/productdetail?partno=GRM188R60J476ME15%23"
			(at 21.59 107.95 0)
			(effects
				(font
					(size 1.27 1.27)
					(thickness 0.15)
				)
				(justify left bottom)
				(hide yes)
			)
		)
		(property "Description" ""
			(at 36.83 87.63 0)
			(effects
				(font
					(size 1.27 1.27)
				)
				(hide yes)
			)
		)
		(property "Manufacturer" "Murata"
			(at 16.51 107.95 0)
			(effects
				(font
					(size 1.27 1.27)
					(thickness 0.15)
				)
				(justify left bottom)
				(hide yes)
			)
		)
		(property "MPN" "GRM188R60J476ME15D"
			(at 19.05 107.95 0)
			(effects
				(font
					(size 1.27 1.27)
					(thickness 0.15)
				)
				(justify left bottom)
				(hide yes)
			)
		)
		(property "Val" "47u"
			(at 37.465 92.075 90)
			(effects
				(font
					(size 1.27 1.27)
					(thickness 0.15)
				)
				(justify left)
			)
		)
		(property "License" "Apache-2.0"
			(at 13.97 107.95 0)
			(effects
				(font
					(size 1.27 1.27)
					(thickness 0.15)
				)
				(justify left bottom)
				(hide yes)
			)
		)
		(property "Author" "Antmicro"
			(at 11.43 107.95 0)
			(effects
				(font
					(size 1.27 1.27)
					(thickness 0.15)
				)
				(justify left bottom)
				(hide yes)
			)
		)
		(property "Voltage" ""
			(at 8.89 107.95 0)
			(effects
				(font
					(size 1.27 1.27)
				)
				(justify left bottom)
				(hide yes)
			)
		)
		(property "Dielectric" ""
			(at 6.35 107.95 0)
			(effects
				(font
					(size 1.27 1.27)
				)
				(justify left bottom)
				(hide yes)
			)
		)
		(pin "1"
		)
		(pin "2"
		)
		(instances
			(project "data-center-rdimm-ddr5-tester"
				(path ""
					(reference "C62")
					(unit 1)
				)
			)
		)
	)
	(symbol
		(lib_id "antmicroCapacitorsmisc:C_100u_0805")
		(at 107.95 66.04 90)
		(unit 1)
		(exclude_from_sim no)
		(in_bom yes)
		(on_board yes)
		(dnp no)
		(fields_autoplaced yes)
		(property "Reference" "C242"
			(at 110.49 62.2236 90)
			(effects
				(font
					(size 1.27 1.27)
					(thickness 0.15)
				)
				(justify right)
			)
		)
		(property "Value" "C_100u_0805"
			(at 118.11 45.72 0)
			(effects
				(font
					(size 1.27 1.27)
					(thickness 0.15)
				)
				(justify left bottom)
				(hide yes)
			)
		)
		(property "Footprint" "antmicro-footprints:C_0805_2012Metric"
			(at 120.65 45.72 0)
			(effects
				(font
					(size 1.27 1.27)
					(thickness 0.15)
				)
				(justify left bottom)
				(hide yes)
			)
		)
		(property "Datasheet" "https://www.murata.com/products/productdetail?partno=GRM21BR60J107ME15%23"
			(at 123.19 45.72 0)
			(effects
				(font
					(size 1.27 1.27)
					(thickness 0.15)
				)
				(justify left bottom)
				(hide yes)
			)
		)
		(property "Description" ""
			(at 107.95 66.04 0)
			(effects
				(font
					(size 1.27 1.27)
				)
				(hide yes)
			)
		)
		(property "MPN" "GRM21BR60J107ME15L"
			(at 125.73 45.72 0)
			(effects
				(font
					(size 1.27 1.27)
					(thickness 0.15)
				)
				(justify left bottom)
				(hide yes)
			)
		)
		(property "Manufacturer" "Murata"
			(at 128.27 45.72 0)
			(effects
				(font
					(size 1.27 1.27)
					(thickness 0.15)
				)
				(justify left bottom)
				(hide yes)
			)
		)
		(property "License" "Apache-2.0"
			(at 130.81 45.72 0)
			(effects
				(font
					(size 1.27 1.27)
					(thickness 0.15)
				)
				(justify left bottom)
				(hide yes)
			)
		)
		(property "Author" "Antmicro"
			(at 133.35 45.72 0)
			(effects
				(font
					(size 1.27 1.27)
					(thickness 0.15)
				)
				(justify left bottom)
				(hide yes)
			)
		)
		(property "Val" "100u"
			(at 110.49 64.7636 90)
			(effects
				(font
					(size 1.27 1.27)
					(thickness 0.15)
				)
				(justify right)
			)
		)
		(property "Voltage" ""
			(at 135.89 45.72 0)
			(effects
				(font
					(size 1.27 1.27)
				)
				(justify left bottom)
				(hide yes)
			)
		)
		(property "Dielectric" ""
			(at 138.43 45.72 0)
			(effects
				(font
					(size 1.27 1.27)
				)
				(justify left bottom)
				(hide yes)
			)
		)
		(property "Public" "False"
			(at 140.97 45.72 0)
			(effects
				(font
					(size 1.27 1.27)
				)
				(justify left bottom)
				(hide yes)
			)
		)
		(pin "1"
		)
		(pin "2"
		)
		(instances
			(project "data-center-rdimm-ddr5-tester"
				(path ""
					(reference "C242")
					(unit 1)
				)
			)
		)
	)
	(symbol
		(lib_id "antmicropower:GND")
		(at 226.06 149.86 0)
		(unit 1)
		(exclude_from_sim no)
		(in_bom yes)
		(on_board yes)
		(dnp no)
		(fields_autoplaced yes)
		(property "Reference" "#PWR041"
			(at 226.06 156.21 0)
			(effects
				(font
					(size 1.27 1.27)
				)
				(hide yes)
			)
		)
		(property "Value" "GND"
			(at 224.155 154.305 0)
			(effects
				(font
					(size 1.27 1.27)
					(thickness 0.15)
				)
				(justify left bottom)
			)
		)
		(property "Footprint" ""
			(at 234.95 157.48 0)
			(effects
				(font
					(size 1.27 1.27)
					(thickness 0.15)
				)
				(justify left bottom)
				(hide yes)
			)
		)
		(property "Datasheet" ""
			(at 234.95 162.56 0)
			(effects
				(font
					(size 1.27 1.27)
					(thickness 0.15)
				)
				(justify left bottom)
				(hide yes)
			)
		)
		(property "Description" ""
			(at 226.06 149.86 0)
			(effects
				(font
					(size 1.27 1.27)
				)
				(hide yes)
			)
		)
		(property "Author" "Antmicro"
			(at 234.95 154.94 0)
			(effects
				(font
					(size 1.27 1.27)
					(thickness 0.15)
				)
				(justify left bottom)
				(hide yes)
			)
		)
		(property "License" "Apache-2.0"
			(at 234.95 157.48 0)
			(effects
				(font
					(size 1.27 1.27)
					(thickness 0.15)
				)
				(justify left bottom)
				(hide yes)
			)
		)
		(pin "1"
		)
		(instances
			(project "data-center-rdimm-ddr5-tester"
				(path ""
					(reference "#PWR041")
					(unit 1)
				)
			)
		)
	)
	(symbol
		(lib_id "antmicropower:+0V85")
		(at 36.83 137.16 0)
		(unit 1)
		(exclude_from_sim no)
		(in_bom yes)
		(on_board yes)
		(dnp no)
		(fields_autoplaced yes)
		(property "Reference" "#PWR0462"
			(at 36.83 140.97 0)
			(effects
				(font
					(size 1.27 1.27)
				)
				(hide yes)
			)
		)
		(property "Value" "+0V85"
			(at 36.83 132.08 0)
			(effects
				(font
					(size 1.27 1.27)
				)
			)
		)
		(property "Footprint" ""
			(at 36.83 137.16 0)
			(effects
				(font
					(size 1.27 1.27)
				)
				(hide yes)
			)
		)
		(property "Datasheet" ""
			(at 36.83 137.16 0)
			(effects
				(font
					(size 1.27 1.27)
				)
				(hide yes)
			)
		)
		(property "Description" ""
			(at 36.83 137.16 0)
			(effects
				(font
					(size 1.27 1.27)
				)
				(hide yes)
			)
		)
		(pin "1"
		)
		(instances
			(project "data-center-rdimm-ddr5-tester"
				(path ""
					(reference "#PWR0462")
					(unit 1)
				)
			)
		)
	)
	(symbol
		(lib_id "antmicroCapacitors0402:C_10u_10V_0402")
		(at 276.86 270.51 90)
		(unit 1)
		(exclude_from_sim no)
		(in_bom yes)
		(on_board yes)
		(dnp no)
		(property "Reference" "C23"
			(at 278.13 266.065 90)
			(effects
				(font
					(size 1.27 1.27)
					(thickness 0.15)
				)
				(justify right)
			)
		)
		(property "Value" "C_10u_10V_0402"
			(at 287.02 250.19 0)
			(effects
				(font
					(size 1.27 1.27)
					(thickness 0.15)
				)
				(justify left bottom)
				(hide yes)
			)
		)
		(property "Footprint" "antmicro-footprints:C_0402_1005Metric_EIA"
			(at 289.56 250.19 0)
			(effects
				(font
					(size 1.27 1.27)
					(thickness 0.15)
				)
				(justify left bottom)
				(hide yes)
			)
		)
		(property "Datasheet" "https://www.murata.com/products/productdetail?partno=GRM155R61A106ME11%23"
			(at 292.1 250.19 0)
			(effects
				(font
					(size 1.27 1.27)
					(thickness 0.15)
				)
				(justify left bottom)
				(hide yes)
			)
		)
		(property "Description" ""
			(at 276.86 270.51 0)
			(effects
				(font
					(size 1.27 1.27)
				)
				(hide yes)
			)
		)
		(property "MPN" "GRM155R61A106ME11D"
			(at 294.64 250.19 0)
			(effects
				(font
					(size 1.27 1.27)
					(thickness 0.15)
				)
				(justify left bottom)
				(hide yes)
			)
		)
		(property "Manufacturer" "Murata"
			(at 297.18 250.19 0)
			(effects
				(font
					(size 1.27 1.27)
					(thickness 0.15)
				)
				(justify left bottom)
				(hide yes)
			)
		)
		(property "License" "Apache-2.0"
			(at 299.72 250.19 0)
			(effects
				(font
					(size 1.27 1.27)
					(thickness 0.15)
				)
				(justify left bottom)
				(hide yes)
			)
		)
		(property "Author" "Antmicro"
			(at 302.26 250.19 0)
			(effects
				(font
					(size 1.27 1.27)
					(thickness 0.15)
				)
				(justify left bottom)
				(hide yes)
			)
		)
		(property "Val" "10u"
			(at 278.13 269.875 90)
			(effects
				(font
					(size 1.27 1.27)
					(thickness 0.15)
				)
				(justify right)
			)
		)
		(property "Voltage" "10V"
			(at 304.8 250.19 0)
			(effects
				(font
					(size 1.27 1.27)
				)
				(justify left bottom)
				(hide yes)
			)
		)
		(property "Dielectric" "X5R"
			(at 307.34 250.19 0)
			(effects
				(font
					(size 1.27 1.27)
				)
				(justify left bottom)
				(hide yes)
			)
		)
		(pin "1"
		)
		(pin "2"
		)
		(instances
			(project "data-center-rdimm-ddr5-tester"
				(path ""
					(reference "C23")
					(unit 1)
				)
			)
		)
	)
	(symbol
		(lib_id "antmicroCapacitors0402:C_1u_25V_0402")
		(at 69.85 147.32 90)
		(unit 1)
		(exclude_from_sim no)
		(in_bom yes)
		(on_board yes)
		(dnp no)
		(fields_autoplaced yes)
		(property "Reference" "C40"
			(at 72.39 143.5036 90)
			(effects
				(font
					(size 1.27 1.27)
					(thickness 0.15)
				)
				(justify right)
			)
		)
		(property "Value" "C_1u_25V_0402"
			(at 80.01 127 0)
			(effects
				(font
					(size 1.27 1.27)
					(thickness 0.15)
				)
				(justify left bottom)
				(hide yes)
			)
		)
		(property "Footprint" "antmicro-footprints:C_0402_1005Metric_EIA"
			(at 82.55 127 0)
			(effects
				(font
					(size 1.27 1.27)
					(thickness 0.15)
				)
				(justify left bottom)
				(hide yes)
			)
		)
		(property "Datasheet" "https://www.murata.com/products/productdetail?partno=GRM155R61E105KE11%23"
			(at 85.09 127 0)
			(effects
				(font
					(size 1.27 1.27)
					(thickness 0.15)
				)
				(justify left bottom)
				(hide yes)
			)
		)
		(property "Description" ""
			(at 69.85 147.32 0)
			(effects
				(font
					(size 1.27 1.27)
				)
				(hide yes)
			)
		)
		(property "MPN" "GRM155R61E105KE11J"
			(at 87.63 127 0)
			(effects
				(font
					(size 1.27 1.27)
					(thickness 0.15)
				)
				(justify left bottom)
				(hide yes)
			)
		)
		(property "Manufacturer" "Murata"
			(at 90.17 127 0)
			(effects
				(font
					(size 1.27 1.27)
					(thickness 0.15)
				)
				(justify left bottom)
				(hide yes)
			)
		)
		(property "License" "Apache-2.0"
			(at 92.71 127 0)
			(effects
				(font
					(size 1.27 1.27)
					(thickness 0.15)
				)
				(justify left bottom)
				(hide yes)
			)
		)
		(property "Author" "Antmicro"
			(at 95.25 127 0)
			(effects
				(font
					(size 1.27 1.27)
					(thickness 0.15)
				)
				(justify left bottom)
				(hide yes)
			)
		)
		(property "Val" "1u"
			(at 72.39 146.0436 90)
			(effects
				(font
					(size 1.27 1.27)
					(thickness 0.15)
				)
				(justify right)
			)
		)
		(property "Voltage" "25V"
			(at 97.79 127 0)
			(effects
				(font
					(size 1.27 1.27)
				)
				(justify left bottom)
				(hide yes)
			)
		)
		(property "Dielectric" "X5R"
			(at 100.33 127 0)
			(effects
				(font
					(size 1.27 1.27)
				)
				(justify left bottom)
				(hide yes)
			)
		)
		(pin "1"
		)
		(pin "2"
		)
		(instances
			(project "data-center-rdimm-ddr5-tester"
				(path ""
					(reference "C40")
					(unit 1)
				)
			)
		)
	)
	(symbol
		(lib_id "antmicropower:GND")
		(at 102.87 173.99 0)
		(unit 1)
		(exclude_from_sim no)
		(in_bom yes)
		(on_board yes)
		(dnp no)
		(fields_autoplaced yes)
		(property "Reference" "#PWR0124"
			(at 102.87 180.34 0)
			(effects
				(font
					(size 1.27 1.27)
				)
				(hide yes)
			)
		)
		(property "Value" "GND"
			(at 100.965 178.435 0)
			(effects
				(font
					(size 1.27 1.27)
					(thickness 0.15)
				)
				(justify left bottom)
			)
		)
		(property "Footprint" ""
			(at 111.76 181.61 0)
			(effects
				(font
					(size 1.27 1.27)
					(thickness 0.15)
				)
				(justify left bottom)
				(hide yes)
			)
		)
		(property "Datasheet" ""
			(at 111.76 186.69 0)
			(effects
				(font
					(size 1.27 1.27)
					(thickness 0.15)
				)
				(justify left bottom)
				(hide yes)
			)
		)
		(property "Description" ""
			(at 102.87 173.99 0)
			(effects
				(font
					(size 1.27 1.27)
				)
				(hide yes)
			)
		)
		(property "Author" "Antmicro"
			(at 111.76 179.07 0)
			(effects
				(font
					(size 1.27 1.27)
					(thickness 0.15)
				)
				(justify left bottom)
				(hide yes)
			)
		)
		(property "License" "Apache-2.0"
			(at 111.76 181.61 0)
			(effects
				(font
					(size 1.27 1.27)
					(thickness 0.15)
				)
				(justify left bottom)
				(hide yes)
			)
		)
		(pin "1"
		)
		(instances
			(project "data-center-rdimm-ddr5-tester"
				(path ""
					(reference "#PWR0124")
					(unit 1)
				)
			)
		)
	)
	(symbol
		(lib_id "antmicropower:GND")
		(at 330.2 134.62 0)
		(unit 1)
		(exclude_from_sim no)
		(in_bom yes)
		(on_board yes)
		(dnp no)
		(fields_autoplaced yes)
		(property "Reference" "#PWR0381"
			(at 330.2 140.97 0)
			(effects
				(font
					(size 1.27 1.27)
				)
				(hide yes)
			)
		)
		(property "Value" "GND"
			(at 328.295 139.065 0)
			(effects
				(font
					(size 1.27 1.27)
					(thickness 0.15)
				)
				(justify left bottom)
			)
		)
		(property "Footprint" ""
			(at 339.09 142.24 0)
			(effects
				(font
					(size 1.27 1.27)
					(thickness 0.15)
				)
				(justify left bottom)
				(hide yes)
			)
		)
		(property "Datasheet" ""
			(at 339.09 147.32 0)
			(effects
				(font
					(size 1.27 1.27)
					(thickness 0.15)
				)
				(justify left bottom)
				(hide yes)
			)
		)
		(property "Description" ""
			(at 330.2 134.62 0)
			(effects
				(font
					(size 1.27 1.27)
				)
				(hide yes)
			)
		)
		(property "Author" "Antmicro"
			(at 339.09 139.7 0)
			(effects
				(font
					(size 1.27 1.27)
					(thickness 0.15)
				)
				(justify left bottom)
				(hide yes)
			)
		)
		(property "License" "Apache-2.0"
			(at 339.09 142.24 0)
			(effects
				(font
					(size 1.27 1.27)
					(thickness 0.15)
				)
				(justify left bottom)
				(hide yes)
			)
		)
		(pin "1"
		)
		(instances
			(project "data-center-rdimm-ddr5-tester"
				(path ""
					(reference "#PWR0381")
					(unit 1)
				)
			)
		)
	)
	(symbol
		(lib_id "antmicropower:GND")
		(at 276.86 241.3 0)
		(unit 1)
		(exclude_from_sim no)
		(in_bom yes)
		(on_board yes)
		(dnp no)
		(fields_autoplaced yes)
		(property "Reference" "#PWR0143"
			(at 276.86 247.65 0)
			(effects
				(font
					(size 1.27 1.27)
				)
				(hide yes)
			)
		)
		(property "Value" "GND"
			(at 274.955 245.745 0)
			(effects
				(font
					(size 1.27 1.27)
					(thickness 0.15)
				)
				(justify left bottom)
			)
		)
		(property "Footprint" ""
			(at 285.75 248.92 0)
			(effects
				(font
					(size 1.27 1.27)
					(thickness 0.15)
				)
				(justify left bottom)
				(hide yes)
			)
		)
		(property "Datasheet" ""
			(at 285.75 254 0)
			(effects
				(font
					(size 1.27 1.27)
					(thickness 0.15)
				)
				(justify left bottom)
				(hide yes)
			)
		)
		(property "Description" ""
			(at 276.86 241.3 0)
			(effects
				(font
					(size 1.27 1.27)
				)
				(hide yes)
			)
		)
		(property "Author" "Antmicro"
			(at 285.75 246.38 0)
			(effects
				(font
					(size 1.27 1.27)
					(thickness 0.15)
				)
				(justify left bottom)
				(hide yes)
			)
		)
		(property "License" "Apache-2.0"
			(at 285.75 248.92 0)
			(effects
				(font
					(size 1.27 1.27)
					(thickness 0.15)
				)
				(justify left bottom)
				(hide yes)
			)
		)
		(pin "1"
		)
		(instances
			(project "data-center-rdimm-ddr5-tester"
				(path ""
					(reference "#PWR0143")
					(unit 1)
				)
			)
		)
	)
	(symbol
		(lib_id "antmicroCapacitors0402:C_100n_0402")
		(at 375.92 64.77 90)
		(unit 1)
		(exclude_from_sim no)
		(in_bom yes)
		(on_board yes)
		(dnp no)
		(property "Reference" "C108"
			(at 376.555 60.325 90)
			(effects
				(font
					(size 1.27 1.27)
					(thickness 0.15)
				)
				(justify right)
			)
		)
		(property "Value" "C_100n_0402"
			(at 386.08 44.45 0)
			(effects
				(font
					(size 1.27 1.27)
					(thickness 0.15)
				)
				(justify left bottom)
				(hide yes)
			)
		)
		(property "Footprint" "antmicro-footprints:C_0402_1005Metric_EIA"
			(at 388.62 44.45 0)
			(effects
				(font
					(size 1.27 1.27)
					(thickness 0.15)
				)
				(justify left bottom)
				(hide yes)
			)
		)
		(property "Datasheet" "https://www.murata.com/products/productdetail?partno=GRM155R61H104KE14%23"
			(at 391.16 44.45 0)
			(effects
				(font
					(size 1.27 1.27)
					(thickness 0.15)
				)
				(justify left bottom)
				(hide yes)
			)
		)
		(property "Description" ""
			(at 375.92 64.77 0)
			(effects
				(font
					(size 1.27 1.27)
				)
				(hide yes)
			)
		)
		(property "MPN" "GRM155R61H104KE14D"
			(at 393.7 44.45 0)
			(effects
				(font
					(size 1.27 1.27)
					(thickness 0.15)
				)
				(justify left bottom)
				(hide yes)
			)
		)
		(property "Manufacturer" "Murata"
			(at 396.24 44.45 0)
			(effects
				(font
					(size 1.27 1.27)
					(thickness 0.15)
				)
				(justify left bottom)
				(hide yes)
			)
		)
		(property "License" "Apache-2.0"
			(at 398.78 44.45 0)
			(effects
				(font
					(size 1.27 1.27)
					(thickness 0.15)
				)
				(justify left bottom)
				(hide yes)
			)
		)
		(property "Author" "Antmicro"
			(at 401.32 44.45 0)
			(effects
				(font
					(size 1.27 1.27)
					(thickness 0.15)
				)
				(justify left bottom)
				(hide yes)
			)
		)
		(property "Val" "100n"
			(at 376.555 64.135 90)
			(effects
				(font
					(size 1.27 1.27)
					(thickness 0.15)
				)
				(justify right)
			)
		)
		(property "Voltage" "50V"
			(at 403.86 44.45 0)
			(effects
				(font
					(size 1.27 1.27)
				)
				(justify left bottom)
				(hide yes)
			)
		)
		(property "Dielectric" "X5R"
			(at 406.4 44.45 0)
			(effects
				(font
					(size 1.27 1.27)
				)
				(justify left bottom)
				(hide yes)
			)
		)
		(pin "1"
		)
		(pin "2"
		)
		(instances
			(project "data-center-rdimm-ddr5-tester"
				(path ""
					(reference "C108")
					(unit 1)
				)
			)
		)
	)
	(symbol
		(lib_id "antmicropower:+3V3")
		(at 269.24 261.62 0)
		(unit 1)
		(exclude_from_sim no)
		(in_bom yes)
		(on_board yes)
		(dnp no)
		(fields_autoplaced yes)
		(property "Reference" "#PWR064"
			(at 269.24 265.43 0)
			(effects
				(font
					(size 1.27 1.27)
				)
				(hide yes)
			)
		)
		(property "Value" "+3V3"
			(at 266.065 259.08 0)
			(effects
				(font
					(size 1.27 1.27)
					(thickness 0.15)
				)
				(justify left bottom)
			)
		)
		(property "Footprint" ""
			(at 284.48 269.24 0)
			(effects
				(font
					(size 1.27 1.27)
					(thickness 0.15)
				)
				(justify left bottom)
				(hide yes)
			)
		)
		(property "Datasheet" ""
			(at 284.48 271.78 0)
			(effects
				(font
					(size 1.27 1.27)
					(thickness 0.15)
				)
				(justify left bottom)
				(hide yes)
			)
		)
		(property "Description" ""
			(at 269.24 261.62 0)
			(effects
				(font
					(size 1.27 1.27)
				)
				(hide yes)
			)
		)
		(property "Author" "Antmicro"
			(at 284.48 264.16 0)
			(effects
				(font
					(size 1.27 1.27)
					(thickness 0.15)
				)
				(justify left bottom)
				(hide yes)
			)
		)
		(property "License" "Apache-2.0"
			(at 284.48 266.7 0)
			(effects
				(font
					(size 1.27 1.27)
					(thickness 0.15)
				)
				(justify left bottom)
				(hide yes)
			)
		)
		(pin "1"
		)
		(instances
			(project "data-center-rdimm-ddr5-tester"
				(path ""
					(reference "#PWR064")
					(unit 1)
				)
			)
		)
	)
	(symbol
		(lib_id "antmicropower:GND")
		(at 107.95 67.31 0)
		(mirror y)
		(unit 1)
		(exclude_from_sim no)
		(in_bom yes)
		(on_board yes)
		(dnp no)
		(fields_autoplaced yes)
		(property "Reference" "#PWR0146"
			(at 107.95 73.66 0)
			(effects
				(font
					(size 1.27 1.27)
				)
				(hide yes)
			)
		)
		(property "Value" "GND"
			(at 109.855 71.755 0)
			(effects
				(font
					(size 1.27 1.27)
					(thickness 0.15)
				)
				(justify left bottom)
			)
		)
		(property "Footprint" ""
			(at 99.06 74.93 0)
			(effects
				(font
					(size 1.27 1.27)
					(thickness 0.15)
				)
				(justify left bottom)
				(hide yes)
			)
		)
		(property "Datasheet" ""
			(at 99.06 80.01 0)
			(effects
				(font
					(size 1.27 1.27)
					(thickness 0.15)
				)
				(justify left bottom)
				(hide yes)
			)
		)
		(property "Description" ""
			(at 107.95 67.31 0)
			(effects
				(font
					(size 1.27 1.27)
				)
				(hide yes)
			)
		)
		(property "Author" "Antmicro"
			(at 99.06 72.39 0)
			(effects
				(font
					(size 1.27 1.27)
					(thickness 0.15)
				)
				(justify left bottom)
				(hide yes)
			)
		)
		(property "License" "Apache-2.0"
			(at 99.06 74.93 0)
			(effects
				(font
					(size 1.27 1.27)
					(thickness 0.15)
				)
				(justify left bottom)
				(hide yes)
			)
		)
		(pin "1"
		)
		(instances
			(project "data-center-rdimm-ddr5-tester"
				(path ""
					(reference "#PWR0146")
					(unit 1)
				)
			)
		)
	)
	(symbol
		(lib_id "antmicropower:+1V8")
		(at 160.02 261.62 0)
		(unit 1)
		(exclude_from_sim no)
		(in_bom yes)
		(on_board yes)
		(dnp no)
		(fields_autoplaced yes)
		(property "Reference" "#PWR0119"
			(at 175.26 264.16 0)
			(effects
				(font
					(size 1.27 1.27)
					(thickness 0.15)
				)
				(justify left bottom)
				(hide yes)
			)
		)
		(property "Value" "+1V8"
			(at 160.02 257.175 0)
			(effects
				(font
					(size 1.27 1.27)
					(thickness 0.15)
				)
			)
		)
		(property "Footprint" ""
			(at 175.26 269.24 0)
			(effects
				(font
					(size 1.27 1.27)
					(thickness 0.15)
				)
				(justify left bottom)
				(hide yes)
			)
		)
		(property "Datasheet" ""
			(at 175.26 271.78 0)
			(effects
				(font
					(size 1.27 1.27)
					(thickness 0.15)
				)
				(justify left bottom)
				(hide yes)
			)
		)
		(property "Description" ""
			(at 160.02 261.62 0)
			(effects
				(font
					(size 1.27 1.27)
				)
				(hide yes)
			)
		)
		(property "Author" "Antmicro"
			(at 175.26 266.7 0)
			(effects
				(font
					(size 1.27 1.27)
					(thickness 0.15)
				)
				(justify left bottom)
				(hide yes)
			)
		)
		(property "License" "Apache-2.0"
			(at 175.26 269.24 0)
			(effects
				(font
					(size 1.27 1.27)
					(thickness 0.15)
				)
				(justify left bottom)
				(hide yes)
			)
		)
		(pin "1"
		)
		(instances
			(project "data-center-rdimm-ddr5-tester"
				(path ""
					(reference "#PWR0119")
					(unit 1)
				)
			)
		)
	)
	(symbol
		(lib_id "antmicroCapacitors0402:C_100n_0402")
		(at 36.83 119.38 90)
		(unit 1)
		(exclude_from_sim no)
		(in_bom yes)
		(on_board yes)
		(dnp no)
		(property "Reference" "C13"
			(at 37.465 114.935 90)
			(effects
				(font
					(size 1.27 1.27)
					(thickness 0.15)
				)
				(justify right)
			)
		)
		(property "Value" "C_100n_0402"
			(at 46.99 99.06 0)
			(effects
				(font
					(size 1.27 1.27)
					(thickness 0.15)
				)
				(justify left bottom)
				(hide yes)
			)
		)
		(property "Footprint" "antmicro-footprints:C_0402_1005Metric_EIA"
			(at 49.53 99.06 0)
			(effects
				(font
					(size 1.27 1.27)
					(thickness 0.15)
				)
				(justify left bottom)
				(hide yes)
			)
		)
		(property "Datasheet" "https://www.murata.com/products/productdetail?partno=GRM155R61H104KE14%23"
			(at 52.07 99.06 0)
			(effects
				(font
					(size 1.27 1.27)
					(thickness 0.15)
				)
				(justify left bottom)
				(hide yes)
			)
		)
		(property "Description" ""
			(at 36.83 119.38 0)
			(effects
				(font
					(size 1.27 1.27)
				)
				(hide yes)
			)
		)
		(property "MPN" "GRM155R61H104KE14D"
			(at 54.61 99.06 0)
			(effects
				(font
					(size 1.27 1.27)
					(thickness 0.15)
				)
				(justify left bottom)
				(hide yes)
			)
		)
		(property "Manufacturer" "Murata"
			(at 57.15 99.06 0)
			(effects
				(font
					(size 1.27 1.27)
					(thickness 0.15)
				)
				(justify left bottom)
				(hide yes)
			)
		)
		(property "License" "Apache-2.0"
			(at 59.69 99.06 0)
			(effects
				(font
					(size 1.27 1.27)
					(thickness 0.15)
				)
				(justify left bottom)
				(hide yes)
			)
		)
		(property "Author" "Antmicro"
			(at 62.23 99.06 0)
			(effects
				(font
					(size 1.27 1.27)
					(thickness 0.15)
				)
				(justify left bottom)
				(hide yes)
			)
		)
		(property "Val" "100n"
			(at 37.465 118.745 90)
			(effects
				(font
					(size 1.27 1.27)
					(thickness 0.15)
				)
				(justify right)
			)
		)
		(property "Voltage" "50V"
			(at 64.77 99.06 0)
			(effects
				(font
					(size 1.27 1.27)
				)
				(justify left bottom)
				(hide yes)
			)
		)
		(property "Dielectric" "X5R"
			(at 67.31 99.06 0)
			(effects
				(font
					(size 1.27 1.27)
				)
				(justify left bottom)
				(hide yes)
			)
		)
		(pin "1"
		)
		(pin "2"
		)
		(instances
			(project "data-center-rdimm-ddr5-tester"
				(path ""
					(reference "C13")
					(unit 1)
				)
			)
		)
	)
	(symbol
		(lib_id "antmicropower:GND")
		(at 111.76 148.59 0)
		(unit 1)
		(exclude_from_sim no)
		(in_bom yes)
		(on_board yes)
		(dnp no)
		(fields_autoplaced yes)
		(property "Reference" "#PWR094"
			(at 111.76 154.94 0)
			(effects
				(font
					(size 1.27 1.27)
				)
				(hide yes)
			)
		)
		(property "Value" "GND"
			(at 109.855 153.035 0)
			(effects
				(font
					(size 1.27 1.27)
					(thickness 0.15)
				)
				(justify left bottom)
			)
		)
		(property "Footprint" ""
			(at 120.65 156.21 0)
			(effects
				(font
					(size 1.27 1.27)
					(thickness 0.15)
				)
				(justify left bottom)
				(hide yes)
			)
		)
		(property "Datasheet" ""
			(at 120.65 161.29 0)
			(effects
				(font
					(size 1.27 1.27)
					(thickness 0.15)
				)
				(justify left bottom)
				(hide yes)
			)
		)
		(property "Description" ""
			(at 111.76 148.59 0)
			(effects
				(font
					(size 1.27 1.27)
				)
				(hide yes)
			)
		)
		(property "Author" "Antmicro"
			(at 120.65 153.67 0)
			(effects
				(font
					(size 1.27 1.27)
					(thickness 0.15)
				)
				(justify left bottom)
				(hide yes)
			)
		)
		(property "License" "Apache-2.0"
			(at 120.65 156.21 0)
			(effects
				(font
					(size 1.27 1.27)
					(thickness 0.15)
				)
				(justify left bottom)
				(hide yes)
			)
		)
		(pin "1"
		)
		(instances
			(project "data-center-rdimm-ddr5-tester"
				(path ""
					(reference "#PWR094")
					(unit 1)
				)
			)
		)
	)
	(symbol
		(lib_id "antmicroCapacitors0402:C_100n_0402")
		(at 87.63 119.38 90)
		(unit 1)
		(exclude_from_sim no)
		(in_bom yes)
		(on_board yes)
		(dnp no)
		(property "Reference" "C55"
			(at 88.265 114.935 90)
			(effects
				(font
					(size 1.27 1.27)
					(thickness 0.15)
				)
				(justify right)
			)
		)
		(property "Value" "C_100n_0402"
			(at 97.79 99.06 0)
			(effects
				(font
					(size 1.27 1.27)
					(thickness 0.15)
				)
				(justify left bottom)
				(hide yes)
			)
		)
		(property "Footprint" "antmicro-footprints:C_0402_1005Metric_EIA"
			(at 100.33 99.06 0)
			(effects
				(font
					(size 1.27 1.27)
					(thickness 0.15)
				)
				(justify left bottom)
				(hide yes)
			)
		)
		(property "Datasheet" "https://www.murata.com/products/productdetail?partno=GRM155R61H104KE14%23"
			(at 102.87 99.06 0)
			(effects
				(font
					(size 1.27 1.27)
					(thickness 0.15)
				)
				(justify left bottom)
				(hide yes)
			)
		)
		(property "Description" ""
			(at 87.63 119.38 0)
			(effects
				(font
					(size 1.27 1.27)
				)
				(hide yes)
			)
		)
		(property "MPN" "GRM155R61H104KE14D"
			(at 105.41 99.06 0)
			(effects
				(font
					(size 1.27 1.27)
					(thickness 0.15)
				)
				(justify left bottom)
				(hide yes)
			)
		)
		(property "Manufacturer" "Murata"
			(at 107.95 99.06 0)
			(effects
				(font
					(size 1.27 1.27)
					(thickness 0.15)
				)
				(justify left bottom)
				(hide yes)
			)
		)
		(property "License" "Apache-2.0"
			(at 110.49 99.06 0)
			(effects
				(font
					(size 1.27 1.27)
					(thickness 0.15)
				)
				(justify left bottom)
				(hide yes)
			)
		)
		(property "Author" "Antmicro"
			(at 113.03 99.06 0)
			(effects
				(font
					(size 1.27 1.27)
					(thickness 0.15)
				)
				(justify left bottom)
				(hide yes)
			)
		)
		(property "Val" "100n"
			(at 88.265 118.745 90)
			(effects
				(font
					(size 1.27 1.27)
					(thickness 0.15)
				)
				(justify right)
			)
		)
		(property "Voltage" "50V"
			(at 115.57 99.06 0)
			(effects
				(font
					(size 1.27 1.27)
				)
				(justify left bottom)
				(hide yes)
			)
		)
		(property "Dielectric" "X5R"
			(at 118.11 99.06 0)
			(effects
				(font
					(size 1.27 1.27)
				)
				(justify left bottom)
				(hide yes)
			)
		)
		(pin "1"
		)
		(pin "2"
		)
		(instances
			(project "data-center-rdimm-ddr5-tester"
				(path ""
					(reference "C55")
					(unit 1)
				)
			)
		)
	)
	(symbol
		(lib_id "antmicropower:+0V9_MGTAVCC")
		(at 340.36 124.46 0)
		(unit 1)
		(exclude_from_sim no)
		(in_bom yes)
		(on_board yes)
		(dnp no)
		(property "Reference" "#PWR0188"
			(at 340.36 128.27 0)
			(effects
				(font
					(size 1.27 1.27)
				)
				(hide yes)
			)
		)
		(property "Value" "+0V9_MGTAVCC"
			(at 340.36 120.015 0)
			(effects
				(font
					(size 1.27 1.27)
				)
			)
		)
		(property "Footprint" ""
			(at 340.36 124.46 0)
			(effects
				(font
					(size 1.27 1.27)
				)
				(hide yes)
			)
		)
		(property "Datasheet" ""
			(at 340.36 124.46 0)
			(effects
				(font
					(size 1.27 1.27)
				)
				(hide yes)
			)
		)
		(property "Description" ""
			(at 340.36 124.46 0)
			(effects
				(font
					(size 1.27 1.27)
				)
				(hide yes)
			)
		)
		(pin "1"
		)
		(instances
			(project "data-center-rdimm-ddr5-tester"
				(path ""
					(reference "#PWR0188")
					(unit 1)
				)
			)
		)
	)
	(symbol
		(lib_id "antmicroCapacitors0402:C_1u_25V_0402")
		(at 78.74 196.85 90)
		(unit 1)
		(exclude_from_sim no)
		(in_bom yes)
		(on_board yes)
		(dnp no)
		(fields_autoplaced yes)
		(property "Reference" "C90"
			(at 81.28 193.0336 90)
			(effects
				(font
					(size 1.27 1.27)
					(thickness 0.15)
				)
				(justify right)
			)
		)
		(property "Value" "C_1u_25V_0402"
			(at 88.9 176.53 0)
			(effects
				(font
					(size 1.27 1.27)
					(thickness 0.15)
				)
				(justify left bottom)
				(hide yes)
			)
		)
		(property "Footprint" "antmicro-footprints:C_0402_1005Metric_EIA"
			(at 91.44 176.53 0)
			(effects
				(font
					(size 1.27 1.27)
					(thickness 0.15)
				)
				(justify left bottom)
				(hide yes)
			)
		)
		(property "Datasheet" "https://www.murata.com/products/productdetail?partno=GRM155R61E105KE11%23"
			(at 93.98 176.53 0)
			(effects
				(font
					(size 1.27 1.27)
					(thickness 0.15)
				)
				(justify left bottom)
				(hide yes)
			)
		)
		(property "Description" ""
			(at 78.74 196.85 0)
			(effects
				(font
					(size 1.27 1.27)
				)
				(hide yes)
			)
		)
		(property "MPN" "GRM155R61E105KE11J"
			(at 96.52 176.53 0)
			(effects
				(font
					(size 1.27 1.27)
					(thickness 0.15)
				)
				(justify left bottom)
				(hide yes)
			)
		)
		(property "Manufacturer" "Murata"
			(at 99.06 176.53 0)
			(effects
				(font
					(size 1.27 1.27)
					(thickness 0.15)
				)
				(justify left bottom)
				(hide yes)
			)
		)
		(property "License" "Apache-2.0"
			(at 101.6 176.53 0)
			(effects
				(font
					(size 1.27 1.27)
					(thickness 0.15)
				)
				(justify left bottom)
				(hide yes)
			)
		)
		(property "Author" "Antmicro"
			(at 104.14 176.53 0)
			(effects
				(font
					(size 1.27 1.27)
					(thickness 0.15)
				)
				(justify left bottom)
				(hide yes)
			)
		)
		(property "Val" "1u"
			(at 81.28 195.5736 90)
			(effects
				(font
					(size 1.27 1.27)
					(thickness 0.15)
				)
				(justify right)
			)
		)
		(property "Voltage" "25V"
			(at 106.68 176.53 0)
			(effects
				(font
					(size 1.27 1.27)
				)
				(justify left bottom)
				(hide yes)
			)
		)
		(property "Dielectric" "X5R"
			(at 109.22 176.53 0)
			(effects
				(font
					(size 1.27 1.27)
				)
				(justify left bottom)
				(hide yes)
			)
		)
		(pin "1"
		)
		(pin "2"
		)
		(instances
			(project "data-center-rdimm-ddr5-tester"
				(path ""
					(reference "C90")
					(unit 1)
				)
			)
		)
	)
	(symbol
		(lib_id "antmicropower:GND")
		(at 224.79 241.3 0)
		(unit 1)
		(exclude_from_sim no)
		(in_bom yes)
		(on_board yes)
		(dnp no)
		(fields_autoplaced yes)
		(property "Reference" "#PWR0123"
			(at 224.79 247.65 0)
			(effects
				(font
					(size 1.27 1.27)
				)
				(hide yes)
			)
		)
		(property "Value" "GND"
			(at 222.885 245.745 0)
			(effects
				(font
					(size 1.27 1.27)
					(thickness 0.15)
				)
				(justify left bottom)
			)
		)
		(property "Footprint" ""
			(at 233.68 248.92 0)
			(effects
				(font
					(size 1.27 1.27)
					(thickness 0.15)
				)
				(justify left bottom)
				(hide yes)
			)
		)
		(property "Datasheet" ""
			(at 233.68 254 0)
			(effects
				(font
					(size 1.27 1.27)
					(thickness 0.15)
				)
				(justify left bottom)
				(hide yes)
			)
		)
		(property "Description" ""
			(at 224.79 241.3 0)
			(effects
				(font
					(size 1.27 1.27)
				)
				(hide yes)
			)
		)
		(property "Author" "Antmicro"
			(at 233.68 246.38 0)
			(effects
				(font
					(size 1.27 1.27)
					(thickness 0.15)
				)
				(justify left bottom)
				(hide yes)
			)
		)
		(property "License" "Apache-2.0"
			(at 233.68 248.92 0)
			(effects
				(font
					(size 1.27 1.27)
					(thickness 0.15)
				)
				(justify left bottom)
				(hide yes)
			)
		)
		(pin "1"
		)
		(instances
			(project "data-center-rdimm-ddr5-tester"
				(path ""
					(reference "#PWR0123")
					(unit 1)
				)
			)
		)
	)
	(symbol
		(lib_id "antmicropower:+0V85")
		(at 36.83 186.69 0)
		(unit 1)
		(exclude_from_sim no)
		(in_bom yes)
		(on_board yes)
		(dnp no)
		(property "Reference" "#PWR0486"
			(at 36.83 190.5 0)
			(effects
				(font
					(size 1.27 1.27)
				)
				(hide yes)
			)
		)
		(property "Value" "+0V85"
			(at 40.005 180.975 0)
			(effects
				(font
					(size 1.27 1.27)
				)
				(justify right)
			)
		)
		(property "Footprint" ""
			(at 36.83 186.69 0)
			(effects
				(font
					(size 1.27 1.27)
				)
				(hide yes)
			)
		)
		(property "Datasheet" ""
			(at 36.83 186.69 0)
			(effects
				(font
					(size 1.27 1.27)
				)
				(hide yes)
			)
		)
		(property "Description" ""
			(at 36.83 186.69 0)
			(effects
				(font
					(size 1.27 1.27)
				)
				(hide yes)
			)
		)
		(pin "1"
		)
		(instances
			(project "data-center-rdimm-ddr5-tester"
				(path ""
					(reference "#PWR0486")
					(unit 1)
				)
			)
		)
	)
	(symbol
		(lib_id "antmicropower:GND")
		(at 375.92 66.04 0)
		(unit 1)
		(exclude_from_sim no)
		(in_bom yes)
		(on_board yes)
		(dnp no)
		(fields_autoplaced yes)
		(property "Reference" "#PWR0168"
			(at 375.92 72.39 0)
			(effects
				(font
					(size 1.27 1.27)
				)
				(hide yes)
			)
		)
		(property "Value" "GND"
			(at 374.015 70.485 0)
			(effects
				(font
					(size 1.27 1.27)
					(thickness 0.15)
				)
				(justify left bottom)
			)
		)
		(property "Footprint" ""
			(at 384.81 73.66 0)
			(effects
				(font
					(size 1.27 1.27)
					(thickness 0.15)
				)
				(justify left bottom)
				(hide yes)
			)
		)
		(property "Datasheet" ""
			(at 384.81 78.74 0)
			(effects
				(font
					(size 1.27 1.27)
					(thickness 0.15)
				)
				(justify left bottom)
				(hide yes)
			)
		)
		(property "Description" ""
			(at 375.92 66.04 0)
			(effects
				(font
					(size 1.27 1.27)
				)
				(hide yes)
			)
		)
		(property "Author" "Antmicro"
			(at 384.81 71.12 0)
			(effects
				(font
					(size 1.27 1.27)
					(thickness 0.15)
				)
				(justify left bottom)
				(hide yes)
			)
		)
		(property "License" "Apache-2.0"
			(at 384.81 73.66 0)
			(effects
				(font
					(size 1.27 1.27)
					(thickness 0.15)
				)
				(justify left bottom)
				(hide yes)
			)
		)
		(pin "1"
		)
		(instances
			(project "data-center-rdimm-ddr5-tester"
				(path ""
					(reference "#PWR0168")
					(unit 1)
				)
			)
		)
	)
	(symbol
		(lib_id "antmicropower:GND")
		(at 53.34 120.65 0)
		(unit 1)
		(exclude_from_sim no)
		(in_bom yes)
		(on_board yes)
		(dnp no)
		(fields_autoplaced yes)
		(property "Reference" "#PWR073"
			(at 53.34 127 0)
			(effects
				(font
					(size 1.27 1.27)
				)
				(hide yes)
			)
		)
		(property "Value" "GND"
			(at 51.435 125.095 0)
			(effects
				(font
					(size 1.27 1.27)
					(thickness 0.15)
				)
				(justify left bottom)
			)
		)
		(property "Footprint" ""
			(at 62.23 128.27 0)
			(effects
				(font
					(size 1.27 1.27)
					(thickness 0.15)
				)
				(justify left bottom)
				(hide yes)
			)
		)
		(property "Datasheet" ""
			(at 62.23 133.35 0)
			(effects
				(font
					(size 1.27 1.27)
					(thickness 0.15)
				)
				(justify left bottom)
				(hide yes)
			)
		)
		(property "Description" ""
			(at 53.34 120.65 0)
			(effects
				(font
					(size 1.27 1.27)
				)
				(hide yes)
			)
		)
		(property "Author" "Antmicro"
			(at 62.23 125.73 0)
			(effects
				(font
					(size 1.27 1.27)
					(thickness 0.15)
				)
				(justify left bottom)
				(hide yes)
			)
		)
		(property "License" "Apache-2.0"
			(at 62.23 128.27 0)
			(effects
				(font
					(size 1.27 1.27)
					(thickness 0.15)
				)
				(justify left bottom)
				(hide yes)
			)
		)
		(pin "1"
		)
		(instances
			(project "data-center-rdimm-ddr5-tester"
				(path ""
					(reference "#PWR073")
					(unit 1)
				)
			)
		)
	)
	(symbol
		(lib_id "antmicroCapacitors0402:C_10u_10V_0402")
		(at 262.89 238.76 90)
		(unit 1)
		(exclude_from_sim no)
		(in_bom yes)
		(on_board yes)
		(dnp no)
		(property "Reference" "C87"
			(at 264.16 234.315 90)
			(effects
				(font
					(size 1.27 1.27)
					(thickness 0.15)
				)
				(justify right)
			)
		)
		(property "Value" "C_10u_10V_0402"
			(at 273.05 218.44 0)
			(effects
				(font
					(size 1.27 1.27)
					(thickness 0.15)
				)
				(justify left bottom)
				(hide yes)
			)
		)
		(property "Footprint" "antmicro-footprints:C_0402_1005Metric_EIA"
			(at 275.59 218.44 0)
			(effects
				(font
					(size 1.27 1.27)
					(thickness 0.15)
				)
				(justify left bottom)
				(hide yes)
			)
		)
		(property "Datasheet" "https://www.murata.com/products/productdetail?partno=GRM155R61A106ME11%23"
			(at 278.13 218.44 0)
			(effects
				(font
					(size 1.27 1.27)
					(thickness 0.15)
				)
				(justify left bottom)
				(hide yes)
			)
		)
		(property "Description" ""
			(at 262.89 238.76 0)
			(effects
				(font
					(size 1.27 1.27)
				)
				(hide yes)
			)
		)
		(property "MPN" "GRM155R61A106ME11D"
			(at 280.67 218.44 0)
			(effects
				(font
					(size 1.27 1.27)
					(thickness 0.15)
				)
				(justify left bottom)
				(hide yes)
			)
		)
		(property "Manufacturer" "Murata"
			(at 283.21 218.44 0)
			(effects
				(font
					(size 1.27 1.27)
					(thickness 0.15)
				)
				(justify left bottom)
				(hide yes)
			)
		)
		(property "License" "Apache-2.0"
			(at 285.75 218.44 0)
			(effects
				(font
					(size 1.27 1.27)
					(thickness 0.15)
				)
				(justify left bottom)
				(hide yes)
			)
		)
		(property "Author" "Antmicro"
			(at 288.29 218.44 0)
			(effects
				(font
					(size 1.27 1.27)
					(thickness 0.15)
				)
				(justify left bottom)
				(hide yes)
			)
		)
		(property "Val" "10u"
			(at 264.16 238.125 90)
			(effects
				(font
					(size 1.27 1.27)
					(thickness 0.15)
				)
				(justify right)
			)
		)
		(property "Voltage" "10V"
			(at 290.83 218.44 0)
			(effects
				(font
					(size 1.27 1.27)
				)
				(justify left bottom)
				(hide yes)
			)
		)
		(property "Dielectric" "X5R"
			(at 293.37 218.44 0)
			(effects
				(font
					(size 1.27 1.27)
				)
				(justify left bottom)
				(hide yes)
			)
		)
		(pin "1"
		)
		(pin "2"
		)
		(instances
			(project "data-center-rdimm-ddr5-tester"
				(path ""
					(reference "C87")
					(unit 1)
				)
			)
		)
	)
	(symbol
		(lib_id "antmicropower:GND")
		(at 369.57 101.6 0)
		(unit 1)
		(exclude_from_sim no)
		(in_bom yes)
		(on_board yes)
		(dnp no)
		(fields_autoplaced yes)
		(property "Reference" "#PWR0495"
			(at 369.57 107.95 0)
			(effects
				(font
					(size 1.27 1.27)
				)
				(hide yes)
			)
		)
		(property "Value" "GND"
			(at 367.665 106.045 0)
			(effects
				(font
					(size 1.27 1.27)
					(thickness 0.15)
				)
				(justify left bottom)
			)
		)
		(property "Footprint" ""
			(at 378.46 109.22 0)
			(effects
				(font
					(size 1.27 1.27)
					(thickness 0.15)
				)
				(justify left bottom)
				(hide yes)
			)
		)
		(property "Datasheet" ""
			(at 378.46 114.3 0)
			(effects
				(font
					(size 1.27 1.27)
					(thickness 0.15)
				)
				(justify left bottom)
				(hide yes)
			)
		)
		(property "Description" ""
			(at 369.57 101.6 0)
			(effects
				(font
					(size 1.27 1.27)
				)
				(hide yes)
			)
		)
		(property "Author" "Antmicro"
			(at 378.46 106.68 0)
			(effects
				(font
					(size 1.27 1.27)
					(thickness 0.15)
				)
				(justify left bottom)
				(hide yes)
			)
		)
		(property "License" "Apache-2.0"
			(at 378.46 109.22 0)
			(effects
				(font
					(size 1.27 1.27)
					(thickness 0.15)
				)
				(justify left bottom)
				(hide yes)
			)
		)
		(pin "1"
		)
		(instances
			(project "data-center-rdimm-ddr5-tester"
				(path ""
					(reference "#PWR0495")
					(unit 1)
				)
			)
		)
	)
	(symbol
		(lib_id "antmicropower:GND")
		(at 87.63 198.12 0)
		(unit 1)
		(exclude_from_sim no)
		(in_bom yes)
		(on_board yes)
		(dnp no)
		(fields_autoplaced yes)
		(property "Reference" "#PWR0142"
			(at 87.63 204.47 0)
			(effects
				(font
					(size 1.27 1.27)
				)
				(hide yes)
			)
		)
		(property "Value" "GND"
			(at 85.725 202.565 0)
			(effects
				(font
					(size 1.27 1.27)
					(thickness 0.15)
				)
				(justify left bottom)
			)
		)
		(property "Footprint" ""
			(at 96.52 205.74 0)
			(effects
				(font
					(size 1.27 1.27)
					(thickness 0.15)
				)
				(justify left bottom)
				(hide yes)
			)
		)
		(property "Datasheet" ""
			(at 96.52 210.82 0)
			(effects
				(font
					(size 1.27 1.27)
					(thickness 0.15)
				)
				(justify left bottom)
				(hide yes)
			)
		)
		(property "Description" ""
			(at 87.63 198.12 0)
			(effects
				(font
					(size 1.27 1.27)
				)
				(hide yes)
			)
		)
		(property "Author" "Antmicro"
			(at 96.52 203.2 0)
			(effects
				(font
					(size 1.27 1.27)
					(thickness 0.15)
				)
				(justify left bottom)
				(hide yes)
			)
		)
		(property "License" "Apache-2.0"
			(at 96.52 205.74 0)
			(effects
				(font
					(size 1.27 1.27)
					(thickness 0.15)
				)
				(justify left bottom)
				(hide yes)
			)
		)
		(pin "1"
		)
		(instances
			(project "data-center-rdimm-ddr5-tester"
				(path ""
					(reference "#PWR0142")
					(unit 1)
				)
			)
		)
	)
	(symbol
		(lib_id "antmicropower:GND")
		(at 53.34 173.99 0)
		(unit 1)
		(exclude_from_sim no)
		(in_bom yes)
		(on_board yes)
		(dnp no)
		(fields_autoplaced yes)
		(property "Reference" "#PWR099"
			(at 53.34 180.34 0)
			(effects
				(font
					(size 1.27 1.27)
				)
				(hide yes)
			)
		)
		(property "Value" "GND"
			(at 51.435 178.435 0)
			(effects
				(font
					(size 1.27 1.27)
					(thickness 0.15)
				)
				(justify left bottom)
			)
		)
		(property "Footprint" ""
			(at 62.23 181.61 0)
			(effects
				(font
					(size 1.27 1.27)
					(thickness 0.15)
				)
				(justify left bottom)
				(hide yes)
			)
		)
		(property "Datasheet" ""
			(at 62.23 186.69 0)
			(effects
				(font
					(size 1.27 1.27)
					(thickness 0.15)
				)
				(justify left bottom)
				(hide yes)
			)
		)
		(property "Description" ""
			(at 53.34 173.99 0)
			(effects
				(font
					(size 1.27 1.27)
				)
				(hide yes)
			)
		)
		(property "Author" "Antmicro"
			(at 62.23 179.07 0)
			(effects
				(font
					(size 1.27 1.27)
					(thickness 0.15)
				)
				(justify left bottom)
				(hide yes)
			)
		)
		(property "License" "Apache-2.0"
			(at 62.23 181.61 0)
			(effects
				(font
					(size 1.27 1.27)
					(thickness 0.15)
				)
				(justify left bottom)
				(hide yes)
			)
		)
		(pin "1"
		)
		(instances
			(project "data-center-rdimm-ddr5-tester"
				(path ""
					(reference "#PWR099")
					(unit 1)
				)
			)
		)
	)
	(symbol
		(lib_id "antmicropower:+1V2_MGTAVTT")
		(at 325.12 91.44 0)
		(unit 1)
		(exclude_from_sim no)
		(in_bom yes)
		(on_board yes)
		(dnp no)
		(fields_autoplaced yes)
		(property "Reference" "#PWR0496"
			(at 325.12 95.25 0)
			(effects
				(font
					(size 1.27 1.27)
				)
				(hide yes)
			)
		)
		(property "Value" "+1V2_MGTAVTT"
			(at 325.12 87.63 0)
			(effects
				(font
					(size 1.27 1.27)
				)
			)
		)
		(property "Footprint" ""
			(at 325.12 91.44 0)
			(effects
				(font
					(size 1.27 1.27)
				)
				(hide yes)
			)
		)
		(property "Datasheet" ""
			(at 325.12 91.44 0)
			(effects
				(font
					(size 1.27 1.27)
				)
				(hide yes)
			)
		)
		(property "Description" ""
			(at 325.12 91.44 0)
			(effects
				(font
					(size 1.27 1.27)
				)
				(hide yes)
			)
		)
		(pin "1"
		)
		(instances
			(project "data-center-rdimm-ddr5-tester"
				(path ""
					(reference "#PWR0496")
					(unit 1)
				)
			)
		)
	)
	(symbol
		(lib_id "antmicropower:GND")
		(at 270.51 241.3 0)
		(unit 1)
		(exclude_from_sim no)
		(in_bom yes)
		(on_board yes)
		(dnp no)
		(fields_autoplaced yes)
		(property "Reference" "#PWR0141"
			(at 270.51 247.65 0)
			(effects
				(font
					(size 1.27 1.27)
				)
				(hide yes)
			)
		)
		(property "Value" "GND"
			(at 268.605 245.745 0)
			(effects
				(font
					(size 1.27 1.27)
					(thickness 0.15)
				)
				(justify left bottom)
			)
		)
		(property "Footprint" ""
			(at 279.4 248.92 0)
			(effects
				(font
					(size 1.27 1.27)
					(thickness 0.15)
				)
				(justify left bottom)
				(hide yes)
			)
		)
		(property "Datasheet" ""
			(at 279.4 254 0)
			(effects
				(font
					(size 1.27 1.27)
					(thickness 0.15)
				)
				(justify left bottom)
				(hide yes)
			)
		)
		(property "Description" ""
			(at 270.51 241.3 0)
			(effects
				(font
					(size 1.27 1.27)
				)
				(hide yes)
			)
		)
		(property "Author" "Antmicro"
			(at 279.4 246.38 0)
			(effects
				(font
					(size 1.27 1.27)
					(thickness 0.15)
				)
				(justify left bottom)
				(hide yes)
			)
		)
		(property "License" "Apache-2.0"
			(at 279.4 248.92 0)
			(effects
				(font
					(size 1.27 1.27)
					(thickness 0.15)
				)
				(justify left bottom)
				(hide yes)
			)
		)
		(pin "1"
		)
		(instances
			(project "data-center-rdimm-ddr5-tester"
				(path ""
					(reference "#PWR0141")
					(unit 1)
				)
			)
		)
	)
	(symbol
		(lib_id "antmicropower:GND")
		(at 328.93 66.04 0)
		(unit 1)
		(exclude_from_sim no)
		(in_bom yes)
		(on_board yes)
		(dnp no)
		(fields_autoplaced yes)
		(property "Reference" "#PWR0380"
			(at 328.93 72.39 0)
			(effects
				(font
					(size 1.27 1.27)
				)
				(hide yes)
			)
		)
		(property "Value" "GND"
			(at 327.025 70.485 0)
			(effects
				(font
					(size 1.27 1.27)
					(thickness 0.15)
				)
				(justify left bottom)
			)
		)
		(property "Footprint" ""
			(at 337.82 73.66 0)
			(effects
				(font
					(size 1.27 1.27)
					(thickness 0.15)
				)
				(justify left bottom)
				(hide yes)
			)
		)
		(property "Datasheet" ""
			(at 337.82 78.74 0)
			(effects
				(font
					(size 1.27 1.27)
					(thickness 0.15)
				)
				(justify left bottom)
				(hide yes)
			)
		)
		(property "Description" ""
			(at 328.93 66.04 0)
			(effects
				(font
					(size 1.27 1.27)
				)
				(hide yes)
			)
		)
		(property "Author" "Antmicro"
			(at 337.82 71.12 0)
			(effects
				(font
					(size 1.27 1.27)
					(thickness 0.15)
				)
				(justify left bottom)
				(hide yes)
			)
		)
		(property "License" "Apache-2.0"
			(at 337.82 73.66 0)
			(effects
				(font
					(size 1.27 1.27)
					(thickness 0.15)
				)
				(justify left bottom)
				(hide yes)
			)
		)
		(pin "1"
		)
		(instances
			(project "data-center-rdimm-ddr5-tester"
				(path ""
					(reference "#PWR0380")
					(unit 1)
				)
			)
		)
	)
	(symbol
		(lib_id "antmicropower:+0V85")
		(at 36.83 107.95 0)
		(unit 1)
		(exclude_from_sim no)
		(in_bom yes)
		(on_board yes)
		(dnp no)
		(property "Reference" "#PWR079"
			(at 36.83 111.76 0)
			(effects
				(font
					(size 1.27 1.27)
				)
				(hide yes)
			)
		)
		(property "Value" "+0V85"
			(at 36.83 103.505 0)
			(effects
				(font
					(size 1.27 1.27)
				)
			)
		)
		(property "Footprint" ""
			(at 36.83 107.95 0)
			(effects
				(font
					(size 1.27 1.27)
				)
				(hide yes)
			)
		)
		(property "Datasheet" ""
			(at 36.83 107.95 0)
			(effects
				(font
					(size 1.27 1.27)
				)
				(hide yes)
			)
		)
		(property "Description" ""
			(at 36.83 107.95 0)
			(effects
				(font
					(size 1.27 1.27)
				)
				(hide yes)
			)
		)
		(pin "1"
		)
		(instances
			(project "data-center-rdimm-ddr5-tester"
				(path ""
					(reference "#PWR079")
					(unit 1)
				)
			)
		)
	)
	(symbol
		(lib_id "antmicroCapacitors0402:C_100n_0402")
		(at 205.74 240.03 90)
		(unit 1)
		(exclude_from_sim no)
		(in_bom yes)
		(on_board yes)
		(dnp no)
		(fields_autoplaced yes)
		(property "Reference" "C60"
			(at 210.185 235.585 90)
			(effects
				(font
					(size 1.27 1.27)
					(thickness 0.15)
				)
				(justify left)
			)
		)
		(property "Value" "C_100n_0402"
			(at 215.9 219.71 0)
			(effects
				(font
					(size 1.27 1.27)
					(thickness 0.15)
				)
				(justify left bottom)
				(hide yes)
			)
		)
		(property "Footprint" "antmicro-footprints:C_0402_1005Metric_EIA"
			(at 218.44 219.71 0)
			(effects
				(font
					(size 1.27 1.27)
					(thickness 0.15)
				)
				(justify left bottom)
				(hide yes)
			)
		)
		(property "Datasheet" "https://www.murata.com/products/productdetail?partno=GRM155R61H104KE14%23"
			(at 220.98 219.71 0)
			(effects
				(font
					(size 1.27 1.27)
					(thickness 0.15)
				)
				(justify left bottom)
				(hide yes)
			)
		)
		(property "Description" ""
			(at 205.74 240.03 0)
			(effects
				(font
					(size 1.27 1.27)
				)
				(hide yes)
			)
		)
		(property "MPN" "GRM155R61H104KE14D"
			(at 223.52 219.71 0)
			(effects
				(font
					(size 1.27 1.27)
					(thickness 0.15)
				)
				(justify left bottom)
				(hide yes)
			)
		)
		(property "Manufacturer" "Murata"
			(at 226.06 219.71 0)
			(effects
				(font
					(size 1.27 1.27)
					(thickness 0.15)
				)
				(justify left bottom)
				(hide yes)
			)
		)
		(property "License" "Apache-2.0"
			(at 228.6 219.71 0)
			(effects
				(font
					(size 1.27 1.27)
					(thickness 0.15)
				)
				(justify left bottom)
				(hide yes)
			)
		)
		(property "Author" "Antmicro"
			(at 231.14 219.71 0)
			(effects
				(font
					(size 1.27 1.27)
					(thickness 0.15)
				)
				(justify left bottom)
				(hide yes)
			)
		)
		(property "Val" "100n"
			(at 211.455 239.395 90)
			(effects
				(font
					(size 1.27 1.27)
					(thickness 0.15)
				)
				(justify left)
			)
		)
		(property "Voltage" "50V"
			(at 233.68 219.71 0)
			(effects
				(font
					(size 1.27 1.27)
				)
				(justify left bottom)
				(hide yes)
			)
		)
		(property "Dielectric" "X5R"
			(at 236.22 219.71 0)
			(effects
				(font
					(size 1.27 1.27)
				)
				(justify left bottom)
				(hide yes)
			)
		)
		(pin "1"
		)
		(pin "2"
		)
		(instances
			(project "data-center-rdimm-ddr5-tester"
				(path ""
					(reference "C60")
					(unit 1)
				)
			)
		)
	)
	(symbol
		(lib_id "antmicropower:VDD")
		(at 157.48 231.14 0)
		(unit 1)
		(exclude_from_sim no)
		(in_bom yes)
		(on_board yes)
		(dnp no)
		(fields_autoplaced yes)
		(property "Reference" "#PWR0547"
			(at 157.48 234.95 0)
			(effects
				(font
					(size 1.27 1.27)
				)
				(hide yes)
			)
		)
		(property "Value" "VDDQ"
			(at 157.48 226.06 0)
			(effects
				(font
					(size 1.27 1.27)
				)
			)
		)
		(property "Footprint" ""
			(at 157.48 231.14 0)
			(effects
				(font
					(size 1.27 1.27)
				)
				(hide yes)
			)
		)
		(property "Datasheet" ""
			(at 157.48 231.14 0)
			(effects
				(font
					(size 1.27 1.27)
				)
				(hide yes)
			)
		)
		(property "Description" ""
			(at 157.48 231.14 0)
			(effects
				(font
					(size 1.27 1.27)
				)
				(hide yes)
			)
		)
		(pin "1"
		)
		(instances
			(project "data-center-rdimm-ddr5-tester"
				(path ""
					(reference "#PWR0547")
					(unit 1)
				)
			)
		)
	)
	(symbol
		(lib_id "antmicroCapacitors0402:C_100n_0402")
		(at 354.33 100.33 90)
		(unit 1)
		(exclude_from_sim no)
		(in_bom yes)
		(on_board yes)
		(dnp no)
		(property "Reference" "C310"
			(at 354.965 95.885 90)
			(effects
				(font
					(size 1.27 1.27)
					(thickness 0.15)
				)
				(justify right)
			)
		)
		(property "Value" "C_100n_0402"
			(at 364.49 80.01 0)
			(effects
				(font
					(size 1.27 1.27)
					(thickness 0.15)
				)
				(justify left bottom)
				(hide yes)
			)
		)
		(property "Footprint" "antmicro-footprints:C_0402_1005Metric_EIA"
			(at 367.03 80.01 0)
			(effects
				(font
					(size 1.27 1.27)
					(thickness 0.15)
				)
				(justify left bottom)
				(hide yes)
			)
		)
		(property "Datasheet" "https://www.murata.com/products/productdetail?partno=GRM155R61H104KE14%23"
			(at 369.57 80.01 0)
			(effects
				(font
					(size 1.27 1.27)
					(thickness 0.15)
				)
				(justify left bottom)
				(hide yes)
			)
		)
		(property "Description" ""
			(at 354.33 100.33 0)
			(effects
				(font
					(size 1.27 1.27)
				)
				(hide yes)
			)
		)
		(property "MPN" "GRM155R61H104KE14D"
			(at 372.11 80.01 0)
			(effects
				(font
					(size 1.27 1.27)
					(thickness 0.15)
				)
				(justify left bottom)
				(hide yes)
			)
		)
		(property "Manufacturer" "Murata"
			(at 374.65 80.01 0)
			(effects
				(font
					(size 1.27 1.27)
					(thickness 0.15)
				)
				(justify left bottom)
				(hide yes)
			)
		)
		(property "License" "Apache-2.0"
			(at 377.19 80.01 0)
			(effects
				(font
					(size 1.27 1.27)
					(thickness 0.15)
				)
				(justify left bottom)
				(hide yes)
			)
		)
		(property "Author" "Antmicro"
			(at 379.73 80.01 0)
			(effects
				(font
					(size 1.27 1.27)
					(thickness 0.15)
				)
				(justify left bottom)
				(hide yes)
			)
		)
		(property "Val" "100n"
			(at 354.965 99.695 90)
			(effects
				(font
					(size 1.27 1.27)
					(thickness 0.15)
				)
				(justify right)
			)
		)
		(property "Voltage" "50V"
			(at 382.27 80.01 0)
			(effects
				(font
					(size 1.27 1.27)
				)
				(justify left bottom)
				(hide yes)
			)
		)
		(property "Dielectric" "X5R"
			(at 384.81 80.01 0)
			(effects
				(font
					(size 1.27 1.27)
				)
				(justify left bottom)
				(hide yes)
			)
		)
		(pin "1"
		)
		(pin "2"
		)
		(instances
			(project "data-center-rdimm-ddr5-tester"
				(path ""
					(reference "C310")
					(unit 1)
				)
			)
		)
	)
	(symbol
		(lib_id "antmicropower:GND")
		(at 204.47 273.05 0)
		(unit 1)
		(exclude_from_sim no)
		(in_bom yes)
		(on_board yes)
		(dnp no)
		(fields_autoplaced yes)
		(property "Reference" "#PWR0162"
			(at 204.47 279.4 0)
			(effects
				(font
					(size 1.27 1.27)
				)
				(hide yes)
			)
		)
		(property "Value" "GND"
			(at 202.565 277.495 0)
			(effects
				(font
					(size 1.27 1.27)
					(thickness 0.15)
				)
				(justify left bottom)
			)
		)
		(property "Footprint" ""
			(at 213.36 280.67 0)
			(effects
				(font
					(size 1.27 1.27)
					(thickness 0.15)
				)
				(justify left bottom)
				(hide yes)
			)
		)
		(property "Datasheet" ""
			(at 213.36 285.75 0)
			(effects
				(font
					(size 1.27 1.27)
					(thickness 0.15)
				)
				(justify left bottom)
				(hide yes)
			)
		)
		(property "Description" ""
			(at 204.47 273.05 0)
			(effects
				(font
					(size 1.27 1.27)
				)
				(hide yes)
			)
		)
		(property "Author" "Antmicro"
			(at 213.36 278.13 0)
			(effects
				(font
					(size 1.27 1.27)
					(thickness 0.15)
				)
				(justify left bottom)
				(hide yes)
			)
		)
		(property "License" "Apache-2.0"
			(at 213.36 280.67 0)
			(effects
				(font
					(size 1.27 1.27)
					(thickness 0.15)
				)
				(justify left bottom)
				(hide yes)
			)
		)
		(pin "1"
		)
		(instances
			(project "data-center-rdimm-ddr5-tester"
				(path ""
					(reference "#PWR0162")
					(unit 1)
				)
			)
		)
	)
	(symbol
		(lib_id "antmicropower:+3V3")
		(at 204.47 262.89 0)
		(unit 1)
		(exclude_from_sim no)
		(in_bom yes)
		(on_board yes)
		(dnp no)
		(fields_autoplaced yes)
		(property "Reference" "#PWR0159"
			(at 204.47 266.7 0)
			(effects
				(font
					(size 1.27 1.27)
				)
				(hide yes)
			)
		)
		(property "Value" "+3V3"
			(at 201.295 260.35 0)
			(effects
				(font
					(size 1.27 1.27)
					(thickness 0.15)
				)
				(justify left bottom)
			)
		)
		(property "Footprint" ""
			(at 219.71 270.51 0)
			(effects
				(font
					(size 1.27 1.27)
					(thickness 0.15)
				)
				(justify left bottom)
				(hide yes)
			)
		)
		(property "Datasheet" ""
			(at 219.71 273.05 0)
			(effects
				(font
					(size 1.27 1.27)
					(thickness 0.15)
				)
				(justify left bottom)
				(hide yes)
			)
		)
		(property "Description" ""
			(at 204.47 262.89 0)
			(effects
				(font
					(size 1.27 1.27)
				)
				(hide yes)
			)
		)
		(property "Author" "Antmicro"
			(at 219.71 265.43 0)
			(effects
				(font
					(size 1.27 1.27)
					(thickness 0.15)
				)
				(justify left bottom)
				(hide yes)
			)
		)
		(property "License" "Apache-2.0"
			(at 219.71 267.97 0)
			(effects
				(font
					(size 1.27 1.27)
					(thickness 0.15)
				)
				(justify left bottom)
				(hide yes)
			)
		)
		(pin "1"
		)
		(instances
			(project "data-center-rdimm-ddr5-tester"
				(path ""
					(reference "#PWR0159")
					(unit 1)
				)
			)
		)
	)
	(symbol
		(lib_id "antmicropower:GND")
		(at 29.21 242.57 0)
		(mirror y)
		(unit 1)
		(exclude_from_sim no)
		(in_bom yes)
		(on_board yes)
		(dnp no)
		(fields_autoplaced yes)
		(property "Reference" "#PWR052"
			(at 29.21 248.92 0)
			(effects
				(font
					(size 1.27 1.27)
				)
				(hide yes)
			)
		)
		(property "Value" "GND"
			(at 31.115 247.015 0)
			(effects
				(font
					(size 1.27 1.27)
					(thickness 0.15)
				)
				(justify left bottom)
			)
		)
		(property "Footprint" ""
			(at 20.32 250.19 0)
			(effects
				(font
					(size 1.27 1.27)
					(thickness 0.15)
				)
				(justify left bottom)
				(hide yes)
			)
		)
		(property "Datasheet" ""
			(at 20.32 255.27 0)
			(effects
				(font
					(size 1.27 1.27)
					(thickness 0.15)
				)
				(justify left bottom)
				(hide yes)
			)
		)
		(property "Description" ""
			(at 29.21 242.57 0)
			(effects
				(font
					(size 1.27 1.27)
				)
				(hide yes)
			)
		)
		(property "Author" "Antmicro"
			(at 20.32 247.65 0)
			(effects
				(font
					(size 1.27 1.27)
					(thickness 0.15)
				)
				(justify left bottom)
				(hide yes)
			)
		)
		(property "License" "Apache-2.0"
			(at 20.32 250.19 0)
			(effects
				(font
					(size 1.27 1.27)
					(thickness 0.15)
				)
				(justify left bottom)
				(hide yes)
			)
		)
		(pin "1"
		)
		(instances
			(project "data-center-rdimm-ddr5-tester"
				(path ""
					(reference "#PWR052")
					(unit 1)
				)
			)
		)
	)
	(symbol
		(lib_id "antmicroCapacitors0402:C_100n_0402")
		(at 181.61 270.51 90)
		(unit 1)
		(exclude_from_sim no)
		(in_bom yes)
		(on_board yes)
		(dnp no)
		(property "Reference" "C15"
			(at 186.055 266.065 90)
			(effects
				(font
					(size 1.27 1.27)
					(thickness 0.15)
				)
				(justify left)
			)
		)
		(property "Value" "C_100n_0402"
			(at 191.77 250.19 0)
			(effects
				(font
					(size 1.27 1.27)
					(thickness 0.15)
				)
				(justify left bottom)
				(hide yes)
			)
		)
		(property "Footprint" "antmicro-footprints:C_0402_1005Metric_EIA"
			(at 194.31 250.19 0)
			(effects
				(font
					(size 1.27 1.27)
					(thickness 0.15)
				)
				(justify left bottom)
				(hide yes)
			)
		)
		(property "Datasheet" "https://www.murata.com/products/productdetail?partno=GRM155R61H104KE14%23"
			(at 196.85 250.19 0)
			(effects
				(font
					(size 1.27 1.27)
					(thickness 0.15)
				)
				(justify left bottom)
				(hide yes)
			)
		)
		(property "Description" ""
			(at 181.61 270.51 0)
			(effects
				(font
					(size 1.27 1.27)
				)
				(hide yes)
			)
		)
		(property "MPN" "GRM155R61H104KE14D"
			(at 199.39 250.19 0)
			(effects
				(font
					(size 1.27 1.27)
					(thickness 0.15)
				)
				(justify left bottom)
				(hide yes)
			)
		)
		(property "Manufacturer" "Murata"
			(at 201.93 250.19 0)
			(effects
				(font
					(size 1.27 1.27)
					(thickness 0.15)
				)
				(justify left bottom)
				(hide yes)
			)
		)
		(property "License" "Apache-2.0"
			(at 204.47 250.19 0)
			(effects
				(font
					(size 1.27 1.27)
					(thickness 0.15)
				)
				(justify left bottom)
				(hide yes)
			)
		)
		(property "Author" "Antmicro"
			(at 207.01 250.19 0)
			(effects
				(font
					(size 1.27 1.27)
					(thickness 0.15)
				)
				(justify left bottom)
				(hide yes)
			)
		)
		(property "Val" "100n"
			(at 187.325 269.875 90)
			(effects
				(font
					(size 1.27 1.27)
					(thickness 0.15)
				)
				(justify left)
			)
		)
		(property "Voltage" "50V"
			(at 209.55 250.19 0)
			(effects
				(font
					(size 1.27 1.27)
				)
				(justify left bottom)
				(hide yes)
			)
		)
		(property "Dielectric" "X5R"
			(at 212.09 250.19 0)
			(effects
				(font
					(size 1.27 1.27)
				)
				(justify left bottom)
				(hide yes)
			)
		)
		(pin "1"
		)
		(pin "2"
		)
		(instances
			(project "data-center-rdimm-ddr5-tester"
				(path ""
					(reference "C15")
					(unit 1)
				)
			)
		)
	)
	(symbol
		(lib_id "antmicroCapacitors0402:C_1u_25V_0402")
		(at 36.83 172.72 90)
		(unit 1)
		(exclude_from_sim no)
		(in_bom yes)
		(on_board yes)
		(dnp no)
		(fields_autoplaced yes)
		(property "Reference" "C50"
			(at 39.37 168.9036 90)
			(effects
				(font
					(size 1.27 1.27)
					(thickness 0.15)
				)
				(justify right)
			)
		)
		(property "Value" "C_1u_25V_0402"
			(at 46.99 152.4 0)
			(effects
				(font
					(size 1.27 1.27)
					(thickness 0.15)
				)
				(justify left bottom)
				(hide yes)
			)
		)
		(property "Footprint" "antmicro-footprints:C_0402_1005Metric_EIA"
			(at 49.53 152.4 0)
			(effects
				(font
					(size 1.27 1.27)
					(thickness 0.15)
				)
				(justify left bottom)
				(hide yes)
			)
		)
		(property "Datasheet" "https://www.murata.com/products/productdetail?partno=GRM155R61E105KE11%23"
			(at 52.07 152.4 0)
			(effects
				(font
					(size 1.27 1.27)
					(thickness 0.15)
				)
				(justify left bottom)
				(hide yes)
			)
		)
		(property "Description" ""
			(at 36.83 172.72 0)
			(effects
				(font
					(size 1.27 1.27)
				)
				(hide yes)
			)
		)
		(property "MPN" "GRM155R61E105KE11J"
			(at 54.61 152.4 0)
			(effects
				(font
					(size 1.27 1.27)
					(thickness 0.15)
				)
				(justify left bottom)
				(hide yes)
			)
		)
		(property "Manufacturer" "Murata"
			(at 57.15 152.4 0)
			(effects
				(font
					(size 1.27 1.27)
					(thickness 0.15)
				)
				(justify left bottom)
				(hide yes)
			)
		)
		(property "License" "Apache-2.0"
			(at 59.69 152.4 0)
			(effects
				(font
					(size 1.27 1.27)
					(thickness 0.15)
				)
				(justify left bottom)
				(hide yes)
			)
		)
		(property "Author" "Antmicro"
			(at 62.23 152.4 0)
			(effects
				(font
					(size 1.27 1.27)
					(thickness 0.15)
				)
				(justify left bottom)
				(hide yes)
			)
		)
		(property "Val" "1u"
			(at 39.37 171.4436 90)
			(effects
				(font
					(size 1.27 1.27)
					(thickness 0.15)
				)
				(justify right)
			)
		)
		(property "Voltage" "25V"
			(at 64.77 152.4 0)
			(effects
				(font
					(size 1.27 1.27)
				)
				(justify left bottom)
				(hide yes)
			)
		)
		(property "Dielectric" "X5R"
			(at 67.31 152.4 0)
			(effects
				(font
					(size 1.27 1.27)
				)
				(justify left bottom)
				(hide yes)
			)
		)
		(pin "1"
		)
		(pin "2"
		)
		(instances
			(project "data-center-rdimm-ddr5-tester"
				(path ""
					(reference "C50")
					(unit 1)
				)
			)
		)
	)
	(symbol
		(lib_id "antmicropower:+0V85")
		(at 181.61 100.33 0)
		(unit 1)
		(exclude_from_sim no)
		(in_bom yes)
		(on_board yes)
		(dnp no)
		(property "Reference" "#PWR029"
			(at 181.61 104.14 0)
			(effects
				(font
					(size 1.27 1.27)
				)
				(hide yes)
			)
		)
		(property "Value" "+0V85"
			(at 181.61 95.885 0)
			(effects
				(font
					(size 1.27 1.27)
				)
			)
		)
		(property "Footprint" ""
			(at 181.61 100.33 0)
			(effects
				(font
					(size 1.27 1.27)
				)
				(hide yes)
			)
		)
		(property "Datasheet" ""
			(at 181.61 100.33 0)
			(effects
				(font
					(size 1.27 1.27)
				)
				(hide yes)
			)
		)
		(property "Description" ""
			(at 181.61 100.33 0)
			(effects
				(font
					(size 1.27 1.27)
				)
				(hide yes)
			)
		)
		(pin "1"
		)
		(instances
			(project "data-center-rdimm-ddr5-tester"
				(path ""
					(reference "#PWR029")
					(unit 1)
				)
			)
		)
	)
	(symbol
		(lib_id "antmicroCapacitors0402:C_10u_10V_0402")
		(at 40.64 240.03 90)
		(unit 1)
		(exclude_from_sim no)
		(in_bom yes)
		(on_board yes)
		(dnp no)
		(property "Reference" "C30"
			(at 41.91 235.585 90)
			(effects
				(font
					(size 1.27 1.27)
					(thickness 0.15)
				)
				(justify right)
			)
		)
		(property "Value" "C_10u_10V_0402"
			(at 50.8 219.71 0)
			(effects
				(font
					(size 1.27 1.27)
					(thickness 0.15)
				)
				(justify left bottom)
				(hide yes)
			)
		)
		(property "Footprint" "antmicro-footprints:C_0402_1005Metric_EIA"
			(at 53.34 219.71 0)
			(effects
				(font
					(size 1.27 1.27)
					(thickness 0.15)
				)
				(justify left bottom)
				(hide yes)
			)
		)
		(property "Datasheet" "https://www.murata.com/products/productdetail?partno=GRM155R61A106ME11%23"
			(at 55.88 219.71 0)
			(effects
				(font
					(size 1.27 1.27)
					(thickness 0.15)
				)
				(justify left bottom)
				(hide yes)
			)
		)
		(property "Description" ""
			(at 40.64 240.03 0)
			(effects
				(font
					(size 1.27 1.27)
				)
				(hide yes)
			)
		)
		(property "MPN" "GRM155R61A106ME11D"
			(at 58.42 219.71 0)
			(effects
				(font
					(size 1.27 1.27)
					(thickness 0.15)
				)
				(justify left bottom)
				(hide yes)
			)
		)
		(property "Manufacturer" "Murata"
			(at 60.96 219.71 0)
			(effects
				(font
					(size 1.27 1.27)
					(thickness 0.15)
				)
				(justify left bottom)
				(hide yes)
			)
		)
		(property "License" "Apache-2.0"
			(at 63.5 219.71 0)
			(effects
				(font
					(size 1.27 1.27)
					(thickness 0.15)
				)
				(justify left bottom)
				(hide yes)
			)
		)
		(property "Author" "Antmicro"
			(at 66.04 219.71 0)
			(effects
				(font
					(size 1.27 1.27)
					(thickness 0.15)
				)
				(justify left bottom)
				(hide yes)
			)
		)
		(property "Val" "10u"
			(at 41.91 239.395 90)
			(effects
				(font
					(size 1.27 1.27)
					(thickness 0.15)
				)
				(justify right)
			)
		)
		(property "Voltage" "10V"
			(at 68.58 219.71 0)
			(effects
				(font
					(size 1.27 1.27)
				)
				(justify left bottom)
				(hide yes)
			)
		)
		(property "Dielectric" "X5R"
			(at 71.12 219.71 0)
			(effects
				(font
					(size 1.27 1.27)
				)
				(justify left bottom)
				(hide yes)
			)
		)
		(pin "1"
		)
		(pin "2"
		)
		(instances
			(project "data-center-rdimm-ddr5-tester"
				(path ""
					(reference "C30")
					(unit 1)
				)
			)
		)
	)
	(symbol
		(lib_id "antmicropower:GND")
		(at 269.24 273.05 0)
		(unit 1)
		(exclude_from_sim no)
		(in_bom yes)
		(on_board yes)
		(dnp no)
		(fields_autoplaced yes)
		(property "Reference" "#PWR068"
			(at 269.24 279.4 0)
			(effects
				(font
					(size 1.27 1.27)
				)
				(hide yes)
			)
		)
		(property "Value" "GND"
			(at 267.335 277.495 0)
			(effects
				(font
					(size 1.27 1.27)
					(thickness 0.15)
				)
				(justify left bottom)
			)
		)
		(property "Footprint" ""
			(at 278.13 280.67 0)
			(effects
				(font
					(size 1.27 1.27)
					(thickness 0.15)
				)
				(justify left bottom)
				(hide yes)
			)
		)
		(property "Datasheet" ""
			(at 278.13 285.75 0)
			(effects
				(font
					(size 1.27 1.27)
					(thickness 0.15)
				)
				(justify left bottom)
				(hide yes)
			)
		)
		(property "Description" ""
			(at 269.24 273.05 0)
			(effects
				(font
					(size 1.27 1.27)
				)
				(hide yes)
			)
		)
		(property "Author" "Antmicro"
			(at 278.13 278.13 0)
			(effects
				(font
					(size 1.27 1.27)
					(thickness 0.15)
				)
				(justify left bottom)
				(hide yes)
			)
		)
		(property "License" "Apache-2.0"
			(at 278.13 280.67 0)
			(effects
				(font
					(size 1.27 1.27)
					(thickness 0.15)
				)
				(justify left bottom)
				(hide yes)
			)
		)
		(pin "1"
		)
		(instances
			(project "data-center-rdimm-ddr5-tester"
				(path ""
					(reference "#PWR068")
					(unit 1)
				)
			)
		)
	)
	(symbol
		(lib_id "antmicroCapacitors0402:C_100n_0402")
		(at 104.14 119.38 90)
		(unit 1)
		(exclude_from_sim no)
		(in_bom yes)
		(on_board yes)
		(dnp no)
		(property "Reference" "C64"
			(at 104.775 114.935 90)
			(effects
				(font
					(size 1.27 1.27)
					(thickness 0.15)
				)
				(justify right)
			)
		)
		(property "Value" "C_100n_0402"
			(at 114.3 99.06 0)
			(effects
				(font
					(size 1.27 1.27)
					(thickness 0.15)
				)
				(justify left bottom)
				(hide yes)
			)
		)
		(property "Footprint" "antmicro-footprints:C_0402_1005Metric_EIA"
			(at 116.84 99.06 0)
			(effects
				(font
					(size 1.27 1.27)
					(thickness 0.15)
				)
				(justify left bottom)
				(hide yes)
			)
		)
		(property "Datasheet" "https://www.murata.com/products/productdetail?partno=GRM155R61H104KE14%23"
			(at 119.38 99.06 0)
			(effects
				(font
					(size 1.27 1.27)
					(thickness 0.15)
				)
				(justify left bottom)
				(hide yes)
			)
		)
		(property "Description" ""
			(at 104.14 119.38 0)
			(effects
				(font
					(size 1.27 1.27)
				)
				(hide yes)
			)
		)
		(property "MPN" "GRM155R61H104KE14D"
			(at 121.92 99.06 0)
			(effects
				(font
					(size 1.27 1.27)
					(thickness 0.15)
				)
				(justify left bottom)
				(hide yes)
			)
		)
		(property "Manufacturer" "Murata"
			(at 124.46 99.06 0)
			(effects
				(font
					(size 1.27 1.27)
					(thickness 0.15)
				)
				(justify left bottom)
				(hide yes)
			)
		)
		(property "License" "Apache-2.0"
			(at 127 99.06 0)
			(effects
				(font
					(size 1.27 1.27)
					(thickness 0.15)
				)
				(justify left bottom)
				(hide yes)
			)
		)
		(property "Author" "Antmicro"
			(at 129.54 99.06 0)
			(effects
				(font
					(size 1.27 1.27)
					(thickness 0.15)
				)
				(justify left bottom)
				(hide yes)
			)
		)
		(property "Val" "100n"
			(at 104.775 118.745 90)
			(effects
				(font
					(size 1.27 1.27)
					(thickness 0.15)
				)
				(justify right)
			)
		)
		(property "Voltage" "50V"
			(at 132.08 99.06 0)
			(effects
				(font
					(size 1.27 1.27)
				)
				(justify left bottom)
				(hide yes)
			)
		)
		(property "Dielectric" "X5R"
			(at 134.62 99.06 0)
			(effects
				(font
					(size 1.27 1.27)
				)
				(justify left bottom)
				(hide yes)
			)
		)
		(pin "1"
		)
		(pin "2"
		)
		(instances
			(project "data-center-rdimm-ddr5-tester"
				(path ""
					(reference "C64")
					(unit 1)
				)
			)
		)
	)
	(symbol
		(lib_id "antmicroCapacitorsmisc:C_100u_0805")
		(at 80.01 66.04 90)
		(unit 1)
		(exclude_from_sim no)
		(in_bom yes)
		(on_board yes)
		(dnp no)
		(fields_autoplaced yes)
		(property "Reference" "C38"
			(at 82.55 62.2236 90)
			(effects
				(font
					(size 1.27 1.27)
					(thickness 0.15)
				)
				(justify right)
			)
		)
		(property "Value" "C_100u_0805"
			(at 90.17 45.72 0)
			(effects
				(font
					(size 1.27 1.27)
					(thickness 0.15)
				)
				(justify left bottom)
				(hide yes)
			)
		)
		(property "Footprint" "antmicro-footprints:C_0805_2012Metric"
			(at 92.71 45.72 0)
			(effects
				(font
					(size 1.27 1.27)
					(thickness 0.15)
				)
				(justify left bottom)
				(hide yes)
			)
		)
		(property "Datasheet" "https://www.murata.com/products/productdetail?partno=GRM21BR60J107ME15%23"
			(at 95.25 45.72 0)
			(effects
				(font
					(size 1.27 1.27)
					(thickness 0.15)
				)
				(justify left bottom)
				(hide yes)
			)
		)
		(property "Description" ""
			(at 80.01 66.04 0)
			(effects
				(font
					(size 1.27 1.27)
				)
				(hide yes)
			)
		)
		(property "MPN" "GRM21BR60J107ME15L"
			(at 97.79 45.72 0)
			(effects
				(font
					(size 1.27 1.27)
					(thickness 0.15)
				)
				(justify left bottom)
				(hide yes)
			)
		)
		(property "Manufacturer" "Murata"
			(at 100.33 45.72 0)
			(effects
				(font
					(size 1.27 1.27)
					(thickness 0.15)
				)
				(justify left bottom)
				(hide yes)
			)
		)
		(property "License" "Apache-2.0"
			(at 102.87 45.72 0)
			(effects
				(font
					(size 1.27 1.27)
					(thickness 0.15)
				)
				(justify left bottom)
				(hide yes)
			)
		)
		(property "Author" "Antmicro"
			(at 105.41 45.72 0)
			(effects
				(font
					(size 1.27 1.27)
					(thickness 0.15)
				)
				(justify left bottom)
				(hide yes)
			)
		)
		(property "Val" "100u"
			(at 82.55 64.7636 90)
			(effects
				(font
					(size 1.27 1.27)
					(thickness 0.15)
				)
				(justify right)
			)
		)
		(property "Voltage" ""
			(at 107.95 45.72 0)
			(effects
				(font
					(size 1.27 1.27)
				)
				(justify left bottom)
				(hide yes)
			)
		)
		(property "Dielectric" ""
			(at 110.49 45.72 0)
			(effects
				(font
					(size 1.27 1.27)
				)
				(justify left bottom)
				(hide yes)
			)
		)
		(property "Public" "False"
			(at 113.03 45.72 0)
			(effects
				(font
					(size 1.27 1.27)
				)
				(justify left bottom)
				(hide yes)
			)
		)
		(pin "1"
		)
		(pin "2"
		)
		(instances
			(project "data-center-rdimm-ddr5-tester"
				(path ""
					(reference "C38")
					(unit 1)
				)
			)
		)
	)
	(symbol
		(lib_id "antmicroCapacitors0402:C_100n_0402")
		(at 373.38 133.35 90)
		(unit 1)
		(exclude_from_sim no)
		(in_bom yes)
		(on_board yes)
		(dnp no)
		(property "Reference" "C101"
			(at 374.015 128.905 90)
			(effects
				(font
					(size 1.27 1.27)
					(thickness 0.15)
				)
				(justify right)
			)
		)
		(property "Value" "C_100n_0402"
			(at 383.54 113.03 0)
			(effects
				(font
					(size 1.27 1.27)
					(thickness 0.15)
				)
				(justify left bottom)
				(hide yes)
			)
		)
		(property "Footprint" "antmicro-footprints:C_0402_1005Metric_EIA"
			(at 386.08 113.03 0)
			(effects
				(font
					(size 1.27 1.27)
					(thickness 0.15)
				)
				(justify left bottom)
				(hide yes)
			)
		)
		(property "Datasheet" "https://www.murata.com/products/productdetail?partno=GRM155R61H104KE14%23"
			(at 388.62 113.03 0)
			(effects
				(font
					(size 1.27 1.27)
					(thickness 0.15)
				)
				(justify left bottom)
				(hide yes)
			)
		)
		(property "Description" ""
			(at 373.38 133.35 0)
			(effects
				(font
					(size 1.27 1.27)
				)
				(hide yes)
			)
		)
		(property "MPN" "GRM155R61H104KE14D"
			(at 391.16 113.03 0)
			(effects
				(font
					(size 1.27 1.27)
					(thickness 0.15)
				)
				(justify left bottom)
				(hide yes)
			)
		)
		(property "Manufacturer" "Murata"
			(at 393.7 113.03 0)
			(effects
				(font
					(size 1.27 1.27)
					(thickness 0.15)
				)
				(justify left bottom)
				(hide yes)
			)
		)
		(property "License" "Apache-2.0"
			(at 396.24 113.03 0)
			(effects
				(font
					(size 1.27 1.27)
					(thickness 0.15)
				)
				(justify left bottom)
				(hide yes)
			)
		)
		(property "Author" "Antmicro"
			(at 398.78 113.03 0)
			(effects
				(font
					(size 1.27 1.27)
					(thickness 0.15)
				)
				(justify left bottom)
				(hide yes)
			)
		)
		(property "Val" "100n"
			(at 374.015 132.715 90)
			(effects
				(font
					(size 1.27 1.27)
					(thickness 0.15)
				)
				(justify right)
			)
		)
		(property "Voltage" "50V"
			(at 401.32 113.03 0)
			(effects
				(font
					(size 1.27 1.27)
				)
				(justify left bottom)
				(hide yes)
			)
		)
		(property "Dielectric" "X5R"
			(at 403.86 113.03 0)
			(effects
				(font
					(size 1.27 1.27)
				)
				(justify left bottom)
				(hide yes)
			)
		)
		(pin "1"
		)
		(pin "2"
		)
		(instances
			(project "data-center-rdimm-ddr5-tester"
				(path ""
					(reference "C101")
					(unit 1)
				)
			)
		)
	)
	(symbol
		(lib_id "antmicroCapacitorspol:C_Pol_1m_2.5V_KEMET-T520-D")
		(at 49.53 60.96 270)
		(unit 1)
		(exclude_from_sim no)
		(in_bom yes)
		(on_board yes)
		(dnp no)
		(fields_autoplaced yes)
		(property "Reference" "C32"
			(at 51.943 62.136 90)
			(effects
				(font
					(size 1.27 1.27)
					(thickness 0.15)
				)
				(justify left)
			)
		)
		(property "Value" "C_Pol_1m_2.5V_KEMET-T520-D"
			(at 46.99 74.93 0)
			(effects
				(font
					(size 1.27 1.27)
					(thickness 0.15)
				)
				(justify left bottom)
				(hide yes)
			)
		)
		(property "Footprint" "antmicro-footprints:C_Pol_EIA-D"
			(at 41.91 74.93 0)
			(effects
				(font
					(size 1.27 1.27)
					(thickness 0.15)
				)
				(justify left bottom)
				(hide yes)
			)
		)
		(property "Datasheet" "https://www.kemet.com/en/us/capacitors/product/T520D108M2R5ATE030.html"
			(at 39.37 74.93 0)
			(effects
				(font
					(size 1.27 1.27)
					(thickness 0.15)
				)
				(justify left bottom)
				(hide yes)
			)
		)
		(property "Description" ""
			(at 49.53 60.96 0)
			(effects
				(font
					(size 1.27 1.27)
				)
				(hide yes)
			)
		)
		(property "MPN" "T520D108M2R5ATE030"
			(at 36.83 74.93 0)
			(effects
				(font
					(size 1.27 1.27)
					(thickness 0.15)
				)
				(justify left bottom)
				(hide yes)
			)
		)
		(property "Manufacturer" "KEMET"
			(at 34.29 74.93 0)
			(effects
				(font
					(size 1.27 1.27)
					(thickness 0.15)
				)
				(justify left bottom)
				(hide yes)
			)
		)
		(property "License" "Apache-2.0"
			(at 31.75 74.93 0)
			(effects
				(font
					(size 1.27 1.27)
					(thickness 0.15)
				)
				(justify left bottom)
				(hide yes)
			)
		)
		(property "Author" "Antmicro"
			(at 29.21 74.93 0)
			(effects
				(font
					(size 1.27 1.27)
					(thickness 0.15)
				)
				(justify left bottom)
				(hide yes)
			)
		)
		(property "Val" "1000u"
			(at 51.943 64.6597 90)
			(effects
				(font
					(size 1.27 1.27)
					(thickness 0.15)
				)
				(justify left)
			)
		)
		(property "Voltage" "2.5V"
			(at 26.67 74.93 0)
			(effects
				(font
					(size 1.27 1.27)
				)
				(justify left bottom)
				(hide yes)
			)
		)
		(property "Dielectric" "template_dielectric"
			(at 24.13 74.93 0)
			(effects
				(font
					(size 1.27 1.27)
				)
				(justify left bottom)
				(hide yes)
			)
		)
		(pin "1"
		)
		(pin "2"
		)
		(instances
			(project "data-center-rdimm-ddr5-tester"
				(path ""
					(reference "C32")
					(unit 1)
				)
			)
		)
	)
	(symbol
		(lib_id "antmicropower:GND")
		(at 53.34 198.12 0)
		(unit 1)
		(exclude_from_sim no)
		(in_bom yes)
		(on_board yes)
		(dnp no)
		(fields_autoplaced yes)
		(property "Reference" "#PWR0133"
			(at 53.34 204.47 0)
			(effects
				(font
					(size 1.27 1.27)
				)
				(hide yes)
			)
		)
		(property "Value" "GND"
			(at 51.435 202.565 0)
			(effects
				(font
					(size 1.27 1.27)
					(thickness 0.15)
				)
				(justify left bottom)
			)
		)
		(property "Footprint" ""
			(at 62.23 205.74 0)
			(effects
				(font
					(size 1.27 1.27)
					(thickness 0.15)
				)
				(justify left bottom)
				(hide yes)
			)
		)
		(property "Datasheet" ""
			(at 62.23 210.82 0)
			(effects
				(font
					(size 1.27 1.27)
					(thickness 0.15)
				)
				(justify left bottom)
				(hide yes)
			)
		)
		(property "Description" ""
			(at 53.34 198.12 0)
			(effects
				(font
					(size 1.27 1.27)
				)
				(hide yes)
			)
		)
		(property "Author" "Antmicro"
			(at 62.23 203.2 0)
			(effects
				(font
					(size 1.27 1.27)
					(thickness 0.15)
				)
				(justify left bottom)
				(hide yes)
			)
		)
		(property "License" "Apache-2.0"
			(at 62.23 205.74 0)
			(effects
				(font
					(size 1.27 1.27)
					(thickness 0.15)
				)
				(justify left bottom)
				(hide yes)
			)
		)
		(pin "1"
		)
		(instances
			(project "data-center-rdimm-ddr5-tester"
				(path ""
					(reference "#PWR0133")
					(unit 1)
				)
			)
		)
	)
	(symbol
		(lib_id "antmicropower:GND")
		(at 340.36 134.62 0)
		(unit 1)
		(exclude_from_sim no)
		(in_bom yes)
		(on_board yes)
		(dnp no)
		(fields_autoplaced yes)
		(property "Reference" "#PWR0158"
			(at 340.36 140.97 0)
			(effects
				(font
					(size 1.27 1.27)
				)
				(hide yes)
			)
		)
		(property "Value" "GND"
			(at 338.455 139.065 0)
			(effects
				(font
					(size 1.27 1.27)
					(thickness 0.15)
				)
				(justify left bottom)
			)
		)
		(property "Footprint" ""
			(at 349.25 142.24 0)
			(effects
				(font
					(size 1.27 1.27)
					(thickness 0.15)
				)
				(justify left bottom)
				(hide yes)
			)
		)
		(property "Datasheet" ""
			(at 349.25 147.32 0)
			(effects
				(font
					(size 1.27 1.27)
					(thickness 0.15)
				)
				(justify left bottom)
				(hide yes)
			)
		)
		(property "Description" ""
			(at 340.36 134.62 0)
			(effects
				(font
					(size 1.27 1.27)
				)
				(hide yes)
			)
		)
		(property "Author" "Antmicro"
			(at 349.25 139.7 0)
			(effects
				(font
					(size 1.27 1.27)
					(thickness 0.15)
				)
				(justify left bottom)
				(hide yes)
			)
		)
		(property "License" "Apache-2.0"
			(at 349.25 142.24 0)
			(effects
				(font
					(size 1.27 1.27)
					(thickness 0.15)
				)
				(justify left bottom)
				(hide yes)
			)
		)
		(pin "1"
		)
		(instances
			(project "data-center-rdimm-ddr5-tester"
				(path ""
					(reference "#PWR0158")
					(unit 1)
				)
			)
		)
	)
	(symbol
		(lib_id "antmicropower:GND")
		(at 355.6 175.26 0)
		(unit 1)
		(exclude_from_sim no)
		(in_bom yes)
		(on_board yes)
		(dnp no)
		(fields_autoplaced yes)
		(property "Reference" "#PWR0148"
			(at 355.6 181.61 0)
			(effects
				(font
					(size 1.27 1.27)
				)
				(hide yes)
			)
		)
		(property "Value" "GND"
			(at 353.695 179.705 0)
			(effects
				(font
					(size 1.27 1.27)
					(thickness 0.15)
				)
				(justify left bottom)
			)
		)
		(property "Footprint" ""
			(at 364.49 182.88 0)
			(effects
				(font
					(size 1.27 1.27)
					(thickness 0.15)
				)
				(justify left bottom)
				(hide yes)
			)
		)
		(property "Datasheet" ""
			(at 364.49 187.96 0)
			(effects
				(font
					(size 1.27 1.27)
					(thickness 0.15)
				)
				(justify left bottom)
				(hide yes)
			)
		)
		(property "Description" ""
			(at 355.6 175.26 0)
			(effects
				(font
					(size 1.27 1.27)
				)
				(hide yes)
			)
		)
		(property "Author" "Antmicro"
			(at 364.49 180.34 0)
			(effects
				(font
					(size 1.27 1.27)
					(thickness 0.15)
				)
				(justify left bottom)
				(hide yes)
			)
		)
		(property "License" "Apache-2.0"
			(at 364.49 182.88 0)
			(effects
				(font
					(size 1.27 1.27)
					(thickness 0.15)
				)
				(justify left bottom)
				(hide yes)
			)
		)
		(pin "1"
		)
		(instances
			(project "data-center-rdimm-ddr5-tester"
				(path ""
					(reference "#PWR0148")
					(unit 1)
				)
			)
		)
	)
	(symbol
		(lib_id "antmicroCapacitors0603:C_47u_0603")
		(at 29.21 234.95 270)
		(unit 1)
		(exclude_from_sim no)
		(in_bom yes)
		(on_board yes)
		(dnp no)
		(property "Reference" "C11"
			(at 29.21 235.585 90)
			(effects
				(font
					(size 1.27 1.27)
				)
				(justify left)
			)
		)
		(property "Value" "C_47u_0603"
			(at 19.05 255.27 0)
			(effects
				(font
					(size 1.27 1.27)
					(thickness 0.15)
				)
				(justify left bottom)
				(hide yes)
			)
		)
		(property "Footprint" "antmicro-footprints:C_0603_1608Metric"
			(at 16.51 255.27 0)
			(effects
				(font
					(size 1.27 1.27)
					(thickness 0.15)
				)
				(justify left bottom)
				(hide yes)
			)
		)
		(property "Datasheet" "https://www.murata.com/products/productdetail?partno=GRM188R60J476ME15%23"
			(at 13.97 255.27 0)
			(effects
				(font
					(size 1.27 1.27)
					(thickness 0.15)
				)
				(justify left bottom)
				(hide yes)
			)
		)
		(property "Description" ""
			(at 29.21 234.95 0)
			(effects
				(font
					(size 1.27 1.27)
				)
				(hide yes)
			)
		)
		(property "Manufacturer" "Murata"
			(at 8.89 255.27 0)
			(effects
				(font
					(size 1.27 1.27)
					(thickness 0.15)
				)
				(justify left bottom)
				(hide yes)
			)
		)
		(property "MPN" "GRM188R60J476ME15D"
			(at 11.43 255.27 0)
			(effects
				(font
					(size 1.27 1.27)
					(thickness 0.15)
				)
				(justify left bottom)
				(hide yes)
			)
		)
		(property "Val" "47u"
			(at 29.21 239.395 90)
			(effects
				(font
					(size 1.27 1.27)
					(thickness 0.15)
				)
				(justify left)
			)
		)
		(property "License" "Apache-2.0"
			(at 6.35 255.27 0)
			(effects
				(font
					(size 1.27 1.27)
					(thickness 0.15)
				)
				(justify left bottom)
				(hide yes)
			)
		)
		(property "Author" "Antmicro"
			(at 3.81 255.27 0)
			(effects
				(font
					(size 1.27 1.27)
					(thickness 0.15)
				)
				(justify left bottom)
				(hide yes)
			)
		)
		(property "Voltage" ""
			(at 1.27 255.27 0)
			(effects
				(font
					(size 1.27 1.27)
				)
				(justify left bottom)
				(hide yes)
			)
		)
		(property "Dielectric" ""
			(at -1.27 255.27 0)
			(effects
				(font
					(size 1.27 1.27)
				)
				(justify left bottom)
				(hide yes)
			)
		)
		(pin "1"
		)
		(pin "2"
		)
		(instances
			(project "data-center-rdimm-ddr5-tester"
				(path ""
					(reference "C11")
					(unit 1)
				)
			)
		)
	)
	(symbol
		(lib_id "antmicropower:+1V8_MGTVCCAUX")
		(at 345.44 165.1 0)
		(unit 1)
		(exclude_from_sim no)
		(in_bom yes)
		(on_board yes)
		(dnp no)
		(fields_autoplaced yes)
		(property "Reference" "#PWR031"
			(at 345.44 168.91 0)
			(effects
				(font
					(size 1.27 1.27)
				)
				(hide yes)
			)
		)
		(property "Value" "+1V8_MGTVCCAUX"
			(at 345.44 160.02 0)
			(effects
				(font
					(size 1.27 1.27)
				)
			)
		)
		(property "Footprint" ""
			(at 345.44 165.1 0)
			(effects
				(font
					(size 1.27 1.27)
				)
				(hide yes)
			)
		)
		(property "Datasheet" ""
			(at 345.44 165.1 0)
			(effects
				(font
					(size 1.27 1.27)
				)
				(hide yes)
			)
		)
		(property "Description" ""
			(at 345.44 165.1 0)
			(effects
				(font
					(size 1.27 1.27)
				)
				(hide yes)
			)
		)
		(pin "1"
		)
		(instances
			(project "data-center-rdimm-ddr5-tester"
				(path ""
					(reference "#PWR031")
					(unit 1)
				)
			)
		)
	)
	(symbol
		(lib_id "antmicroCapacitors0402:C_100n_0402")
		(at 361.95 100.33 90)
		(unit 1)
		(exclude_from_sim no)
		(in_bom yes)
		(on_board yes)
		(dnp no)
		(property "Reference" "C311"
			(at 362.585 95.885 90)
			(effects
				(font
					(size 1.27 1.27)
					(thickness 0.15)
				)
				(justify right)
			)
		)
		(property "Value" "C_100n_0402"
			(at 372.11 80.01 0)
			(effects
				(font
					(size 1.27 1.27)
					(thickness 0.15)
				)
				(justify left bottom)
				(hide yes)
			)
		)
		(property "Footprint" "antmicro-footprints:C_0402_1005Metric_EIA"
			(at 374.65 80.01 0)
			(effects
				(font
					(size 1.27 1.27)
					(thickness 0.15)
				)
				(justify left bottom)
				(hide yes)
			)
		)
		(property "Datasheet" "https://www.murata.com/products/productdetail?partno=GRM155R61H104KE14%23"
			(at 377.19 80.01 0)
			(effects
				(font
					(size 1.27 1.27)
					(thickness 0.15)
				)
				(justify left bottom)
				(hide yes)
			)
		)
		(property "Description" ""
			(at 361.95 100.33 0)
			(effects
				(font
					(size 1.27 1.27)
				)
				(hide yes)
			)
		)
		(property "MPN" "GRM155R61H104KE14D"
			(at 379.73 80.01 0)
			(effects
				(font
					(size 1.27 1.27)
					(thickness 0.15)
				)
				(justify left bottom)
				(hide yes)
			)
		)
		(property "Manufacturer" "Murata"
			(at 382.27 80.01 0)
			(effects
				(font
					(size 1.27 1.27)
					(thickness 0.15)
				)
				(justify left bottom)
				(hide yes)
			)
		)
		(property "License" "Apache-2.0"
			(at 384.81 80.01 0)
			(effects
				(font
					(size 1.27 1.27)
					(thickness 0.15)
				)
				(justify left bottom)
				(hide yes)
			)
		)
		(property "Author" "Antmicro"
			(at 387.35 80.01 0)
			(effects
				(font
					(size 1.27 1.27)
					(thickness 0.15)
				)
				(justify left bottom)
				(hide yes)
			)
		)
		(property "Val" "100n"
			(at 362.585 99.695 90)
			(effects
				(font
					(size 1.27 1.27)
					(thickness 0.15)
				)
				(justify right)
			)
		)
		(property "Voltage" "50V"
			(at 389.89 80.01 0)
			(effects
				(font
					(size 1.27 1.27)
				)
				(justify left bottom)
				(hide yes)
			)
		)
		(property "Dielectric" "X5R"
			(at 392.43 80.01 0)
			(effects
				(font
					(size 1.27 1.27)
				)
				(justify left bottom)
				(hide yes)
			)
		)
		(pin "1"
		)
		(pin "2"
		)
		(instances
			(project "data-center-rdimm-ddr5-tester"
				(path ""
					(reference "C311")
					(unit 1)
				)
			)
		)
	)
	(symbol
		(lib_id "antmicropower:GND")
		(at 78.74 148.59 0)
		(unit 1)
		(exclude_from_sim no)
		(in_bom yes)
		(on_board yes)
		(dnp no)
		(fields_autoplaced yes)
		(property "Reference" "#PWR088"
			(at 78.74 154.94 0)
			(effects
				(font
					(size 1.27 1.27)
				)
				(hide yes)
			)
		)
		(property "Value" "GND"
			(at 76.835 153.035 0)
			(effects
				(font
					(size 1.27 1.27)
					(thickness 0.15)
				)
				(justify left bottom)
			)
		)
		(property "Footprint" ""
			(at 87.63 156.21 0)
			(effects
				(font
					(size 1.27 1.27)
					(thickness 0.15)
				)
				(justify left bottom)
				(hide yes)
			)
		)
		(property "Datasheet" ""
			(at 87.63 161.29 0)
			(effects
				(font
					(size 1.27 1.27)
					(thickness 0.15)
				)
				(justify left bottom)
				(hide yes)
			)
		)
		(property "Description" ""
			(at 78.74 148.59 0)
			(effects
				(font
					(size 1.27 1.27)
				)
				(hide yes)
			)
		)
		(property "Author" "Antmicro"
			(at 87.63 153.67 0)
			(effects
				(font
					(size 1.27 1.27)
					(thickness 0.15)
				)
				(justify left bottom)
				(hide yes)
			)
		)
		(property "License" "Apache-2.0"
			(at 87.63 156.21 0)
			(effects
				(font
					(size 1.27 1.27)
					(thickness 0.15)
				)
				(justify left bottom)
				(hide yes)
			)
		)
		(pin "1"
		)
		(instances
			(project "data-center-rdimm-ddr5-tester"
				(path ""
					(reference "#PWR088")
					(unit 1)
				)
			)
		)
	)
	(symbol
		(lib_id "antmicroCapacitors0603:C_47u_0603")
		(at 118.11 60.96 270)
		(unit 1)
		(exclude_from_sim no)
		(in_bom yes)
		(on_board yes)
		(dnp no)
		(property "Reference" "C239"
			(at 120.015 62.23 90)
			(effects
				(font
					(size 1.27 1.27)
				)
				(justify left)
			)
		)
		(property "Value" "C_47u_0603"
			(at 107.95 81.28 0)
			(effects
				(font
					(size 1.27 1.27)
					(thickness 0.15)
				)
				(justify left bottom)
				(hide yes)
			)
		)
		(property "Footprint" "antmicro-footprints:C_0603_1608Metric"
			(at 105.41 81.28 0)
			(effects
				(font
					(size 1.27 1.27)
					(thickness 0.15)
				)
				(justify left bottom)
				(hide yes)
			)
		)
		(property "Datasheet" "https://www.murata.com/products/productdetail?partno=GRM188R60J476ME15%23"
			(at 102.87 81.28 0)
			(effects
				(font
					(size 1.27 1.27)
					(thickness 0.15)
				)
				(justify left bottom)
				(hide yes)
			)
		)
		(property "Description" ""
			(at 118.11 60.96 0)
			(effects
				(font
					(size 1.27 1.27)
				)
				(hide yes)
			)
		)
		(property "Manufacturer" "Murata"
			(at 97.79 81.28 0)
			(effects
				(font
					(size 1.27 1.27)
					(thickness 0.15)
				)
				(justify left bottom)
				(hide yes)
			)
		)
		(property "MPN" "GRM188R60J476ME15D"
			(at 100.33 81.28 0)
			(effects
				(font
					(size 1.27 1.27)
					(thickness 0.15)
				)
				(justify left bottom)
				(hide yes)
			)
		)
		(property "Val" "47u"
			(at 120.015 64.77 90)
			(effects
				(font
					(size 1.27 1.27)
					(thickness 0.15)
				)
				(justify left)
			)
		)
		(property "License" "Apache-2.0"
			(at 95.25 81.28 0)
			(effects
				(font
					(size 1.27 1.27)
					(thickness 0.15)
				)
				(justify left bottom)
				(hide yes)
			)
		)
		(property "Author" "Antmicro"
			(at 92.71 81.28 0)
			(effects
				(font
					(size 1.27 1.27)
					(thickness 0.15)
				)
				(justify left bottom)
				(hide yes)
			)
		)
		(property "Voltage" ""
			(at 90.17 81.28 0)
			(effects
				(font
					(size 1.27 1.27)
				)
				(justify left bottom)
				(hide yes)
			)
		)
		(property "Dielectric" ""
			(at 87.63 81.28 0)
			(effects
				(font
					(size 1.27 1.27)
				)
				(justify left bottom)
				(hide yes)
			)
		)
		(pin "1"
		)
		(pin "2"
		)
		(instances
			(project "data-center-rdimm-ddr5-tester"
				(path ""
					(reference "C239")
					(unit 1)
				)
			)
		)
	)
	(symbol
		(lib_id "antmicroCapacitors0402:C_1u_25V_0402")
		(at 69.85 196.85 90)
		(unit 1)
		(exclude_from_sim no)
		(in_bom yes)
		(on_board yes)
		(dnp no)
		(fields_autoplaced yes)
		(property "Reference" "C88"
			(at 72.39 193.0336 90)
			(effects
				(font
					(size 1.27 1.27)
					(thickness 0.15)
				)
				(justify right)
			)
		)
		(property "Value" "C_1u_25V_0402"
			(at 80.01 176.53 0)
			(effects
				(font
					(size 1.27 1.27)
					(thickness 0.15)
				)
				(justify left bottom)
				(hide yes)
			)
		)
		(property "Footprint" "antmicro-footprints:C_0402_1005Metric_EIA"
			(at 82.55 176.53 0)
			(effects
				(font
					(size 1.27 1.27)
					(thickness 0.15)
				)
				(justify left bottom)
				(hide yes)
			)
		)
		(property "Datasheet" "https://www.murata.com/products/productdetail?partno=GRM155R61E105KE11%23"
			(at 85.09 176.53 0)
			(effects
				(font
					(size 1.27 1.27)
					(thickness 0.15)
				)
				(justify left bottom)
				(hide yes)
			)
		)
		(property "Description" ""
			(at 69.85 196.85 0)
			(effects
				(font
					(size 1.27 1.27)
				)
				(hide yes)
			)
		)
		(property "MPN" "GRM155R61E105KE11J"
			(at 87.63 176.53 0)
			(effects
				(font
					(size 1.27 1.27)
					(thickness 0.15)
				)
				(justify left bottom)
				(hide yes)
			)
		)
		(property "Manufacturer" "Murata"
			(at 90.17 176.53 0)
			(effects
				(font
					(size 1.27 1.27)
					(thickness 0.15)
				)
				(justify left bottom)
				(hide yes)
			)
		)
		(property "License" "Apache-2.0"
			(at 92.71 176.53 0)
			(effects
				(font
					(size 1.27 1.27)
					(thickness 0.15)
				)
				(justify left bottom)
				(hide yes)
			)
		)
		(property "Author" "Antmicro"
			(at 95.25 176.53 0)
			(effects
				(font
					(size 1.27 1.27)
					(thickness 0.15)
				)
				(justify left bottom)
				(hide yes)
			)
		)
		(property "Val" "1u"
			(at 72.39 195.5736 90)
			(effects
				(font
					(size 1.27 1.27)
					(thickness 0.15)
				)
				(justify right)
			)
		)
		(property "Voltage" "25V"
			(at 97.79 176.53 0)
			(effects
				(font
					(size 1.27 1.27)
				)
				(justify left bottom)
				(hide yes)
			)
		)
		(property "Dielectric" "X5R"
			(at 100.33 176.53 0)
			(effects
				(font
					(size 1.27 1.27)
				)
				(justify left bottom)
				(hide yes)
			)
		)
		(pin "1"
		)
		(pin "2"
		)
		(instances
			(project "data-center-rdimm-ddr5-tester"
				(path ""
					(reference "C88")
					(unit 1)
				)
			)
		)
	)
	(symbol
		(lib_id "antmicropower:+0V85")
		(at 27.94 57.15 0)
		(unit 1)
		(exclude_from_sim no)
		(in_bom yes)
		(on_board yes)
		(dnp no)
		(fields_autoplaced yes)
		(property "Reference" "#PWR053"
			(at 27.94 60.96 0)
			(effects
				(font
					(size 1.27 1.27)
				)
				(hide yes)
			)
		)
		(property "Value" "+0V85"
			(at 27.94 52.07 0)
			(effects
				(font
					(size 1.27 1.27)
				)
			)
		)
		(property "Footprint" ""
			(at 27.94 57.15 0)
			(effects
				(font
					(size 1.27 1.27)
				)
				(hide yes)
			)
		)
		(property "Datasheet" ""
			(at 27.94 57.15 0)
			(effects
				(font
					(size 1.27 1.27)
				)
				(hide yes)
			)
		)
		(property "Description" ""
			(at 27.94 57.15 0)
			(effects
				(font
					(size 1.27 1.27)
				)
				(hide yes)
			)
		)
		(pin "1"
		)
		(instances
			(project "data-center-rdimm-ddr5-tester"
				(path ""
					(reference "#PWR053")
					(unit 1)
				)
			)
		)
	)
	(symbol
		(lib_id "antmicroCapacitors0402:C_100n_0402")
		(at 356.87 133.35 90)
		(unit 1)
		(exclude_from_sim no)
		(in_bom yes)
		(on_board yes)
		(dnp no)
		(property "Reference" "C99"
			(at 357.505 128.905 90)
			(effects
				(font
					(size 1.27 1.27)
					(thickness 0.15)
				)
				(justify right)
			)
		)
		(property "Value" "C_100n_0402"
			(at 367.03 113.03 0)
			(effects
				(font
					(size 1.27 1.27)
					(thickness 0.15)
				)
				(justify left bottom)
				(hide yes)
			)
		)
		(property "Footprint" "antmicro-footprints:C_0402_1005Metric_EIA"
			(at 369.57 113.03 0)
			(effects
				(font
					(size 1.27 1.27)
					(thickness 0.15)
				)
				(justify left bottom)
				(hide yes)
			)
		)
		(property "Datasheet" "https://www.murata.com/products/productdetail?partno=GRM155R61H104KE14%23"
			(at 372.11 113.03 0)
			(effects
				(font
					(size 1.27 1.27)
					(thickness 0.15)
				)
				(justify left bottom)
				(hide yes)
			)
		)
		(property "Description" ""
			(at 356.87 133.35 0)
			(effects
				(font
					(size 1.27 1.27)
				)
				(hide yes)
			)
		)
		(property "MPN" "GRM155R61H104KE14D"
			(at 374.65 113.03 0)
			(effects
				(font
					(size 1.27 1.27)
					(thickness 0.15)
				)
				(justify left bottom)
				(hide yes)
			)
		)
		(property "Manufacturer" "Murata"
			(at 377.19 113.03 0)
			(effects
				(font
					(size 1.27 1.27)
					(thickness 0.15)
				)
				(justify left bottom)
				(hide yes)
			)
		)
		(property "License" "Apache-2.0"
			(at 379.73 113.03 0)
			(effects
				(font
					(size 1.27 1.27)
					(thickness 0.15)
				)
				(justify left bottom)
				(hide yes)
			)
		)
		(property "Author" "Antmicro"
			(at 382.27 113.03 0)
			(effects
				(font
					(size 1.27 1.27)
					(thickness 0.15)
				)
				(justify left bottom)
				(hide yes)
			)
		)
		(property "Val" "100n"
			(at 357.505 132.715 90)
			(effects
				(font
					(size 1.27 1.27)
					(thickness 0.15)
				)
				(justify right)
			)
		)
		(property "Voltage" "50V"
			(at 384.81 113.03 0)
			(effects
				(font
					(size 1.27 1.27)
				)
				(justify left bottom)
				(hide yes)
			)
		)
		(property "Dielectric" "X5R"
			(at 387.35 113.03 0)
			(effects
				(font
					(size 1.27 1.27)
				)
				(justify left bottom)
				(hide yes)
			)
		)
		(pin "1"
		)
		(pin "2"
		)
		(instances
			(project "data-center-rdimm-ddr5-tester"
				(path ""
					(reference "C99")
					(unit 1)
				)
			)
		)
	)
	(symbol
		(lib_id "antmicroCapacitors0402:C_1u_25V_0402")
		(at 44.45 147.32 90)
		(unit 1)
		(exclude_from_sim no)
		(in_bom yes)
		(on_board yes)
		(dnp no)
		(fields_autoplaced yes)
		(property "Reference" "C35"
			(at 46.99 143.5036 90)
			(effects
				(font
					(size 1.27 1.27)
					(thickness 0.15)
				)
				(justify right)
			)
		)
		(property "Value" "C_1u_25V_0402"
			(at 54.61 127 0)
			(effects
				(font
					(size 1.27 1.27)
					(thickness 0.15)
				)
				(justify left bottom)
				(hide yes)
			)
		)
		(property "Footprint" "antmicro-footprints:C_0402_1005Metric_EIA"
			(at 57.15 127 0)
			(effects
				(font
					(size 1.27 1.27)
					(thickness 0.15)
				)
				(justify left bottom)
				(hide yes)
			)
		)
		(property "Datasheet" "https://www.murata.com/products/productdetail?partno=GRM155R61E105KE11%23"
			(at 59.69 127 0)
			(effects
				(font
					(size 1.27 1.27)
					(thickness 0.15)
				)
				(justify left bottom)
				(hide yes)
			)
		)
		(property "Description" ""
			(at 44.45 147.32 0)
			(effects
				(font
					(size 1.27 1.27)
				)
				(hide yes)
			)
		)
		(property "MPN" "GRM155R61E105KE11J"
			(at 62.23 127 0)
			(effects
				(font
					(size 1.27 1.27)
					(thickness 0.15)
				)
				(justify left bottom)
				(hide yes)
			)
		)
		(property "Manufacturer" "Murata"
			(at 64.77 127 0)
			(effects
				(font
					(size 1.27 1.27)
					(thickness 0.15)
				)
				(justify left bottom)
				(hide yes)
			)
		)
		(property "License" "Apache-2.0"
			(at 67.31 127 0)
			(effects
				(font
					(size 1.27 1.27)
					(thickness 0.15)
				)
				(justify left bottom)
				(hide yes)
			)
		)
		(property "Author" "Antmicro"
			(at 69.85 127 0)
			(effects
				(font
					(size 1.27 1.27)
					(thickness 0.15)
				)
				(justify left bottom)
				(hide yes)
			)
		)
		(property "Val" "1u"
			(at 46.99 146.0436 90)
			(effects
				(font
					(size 1.27 1.27)
					(thickness 0.15)
				)
				(justify right)
			)
		)
		(property "Voltage" "25V"
			(at 72.39 127 0)
			(effects
				(font
					(size 1.27 1.27)
				)
				(justify left bottom)
				(hide yes)
			)
		)
		(property "Dielectric" "X5R"
			(at 74.93 127 0)
			(effects
				(font
					(size 1.27 1.27)
				)
				(justify left bottom)
				(hide yes)
			)
		)
		(pin "1"
		)
		(pin "2"
		)
		(instances
			(project "data-center-rdimm-ddr5-tester"
				(path ""
					(reference "C35")
					(unit 1)
				)
			)
		)
	)
	(symbol
		(lib_id "antmicropower:+3V3")
		(at 232.41 261.62 0)
		(unit 1)
		(exclude_from_sim no)
		(in_bom yes)
		(on_board yes)
		(dnp no)
		(fields_autoplaced yes)
		(property "Reference" "#PWR059"
			(at 232.41 265.43 0)
			(effects
				(font
					(size 1.27 1.27)
				)
				(hide yes)
			)
		)
		(property "Value" "+3V3"
			(at 229.235 259.08 0)
			(effects
				(font
					(size 1.27 1.27)
					(thickness 0.15)
				)
				(justify left bottom)
			)
		)
		(property "Footprint" ""
			(at 247.65 269.24 0)
			(effects
				(font
					(size 1.27 1.27)
					(thickness 0.15)
				)
				(justify left bottom)
				(hide yes)
			)
		)
		(property "Datasheet" ""
			(at 247.65 271.78 0)
			(effects
				(font
					(size 1.27 1.27)
					(thickness 0.15)
				)
				(justify left bottom)
				(hide yes)
			)
		)
		(property "Description" ""
			(at 232.41 261.62 0)
			(effects
				(font
					(size 1.27 1.27)
				)
				(hide yes)
			)
		)
		(property "Author" "Antmicro"
			(at 247.65 264.16 0)
			(effects
				(font
					(size 1.27 1.27)
					(thickness 0.15)
				)
				(justify left bottom)
				(hide yes)
			)
		)
		(property "License" "Apache-2.0"
			(at 247.65 266.7 0)
			(effects
				(font
					(size 1.27 1.27)
					(thickness 0.15)
				)
				(justify left bottom)
				(hide yes)
			)
		)
		(pin "1"
		)
		(instances
			(project "data-center-rdimm-ddr5-tester"
				(path ""
					(reference "#PWR059")
					(unit 1)
				)
			)
		)
	)
	(symbol
		(lib_id "antmicropower:GND")
		(at 240.03 273.05 0)
		(unit 1)
		(exclude_from_sim no)
		(in_bom yes)
		(on_board yes)
		(dnp no)
		(fields_autoplaced yes)
		(property "Reference" "#PWR061"
			(at 240.03 279.4 0)
			(effects
				(font
					(size 1.27 1.27)
				)
				(hide yes)
			)
		)
		(property "Value" "GND"
			(at 238.125 277.495 0)
			(effects
				(font
					(size 1.27 1.27)
					(thickness 0.15)
				)
				(justify left bottom)
			)
		)
		(property "Footprint" ""
			(at 248.92 280.67 0)
			(effects
				(font
					(size 1.27 1.27)
					(thickness 0.15)
				)
				(justify left bottom)
				(hide yes)
			)
		)
		(property "Datasheet" ""
			(at 248.92 285.75 0)
			(effects
				(font
					(size 1.27 1.27)
					(thickness 0.15)
				)
				(justify left bottom)
				(hide yes)
			)
		)
		(property "Description" ""
			(at 240.03 273.05 0)
			(effects
				(font
					(size 1.27 1.27)
				)
				(hide yes)
			)
		)
		(property "Author" "Antmicro"
			(at 248.92 278.13 0)
			(effects
				(font
					(size 1.27 1.27)
					(thickness 0.15)
				)
				(justify left bottom)
				(hide yes)
			)
		)
		(property "License" "Apache-2.0"
			(at 248.92 280.67 0)
			(effects
				(font
					(size 1.27 1.27)
					(thickness 0.15)
				)
				(justify left bottom)
				(hide yes)
			)
		)
		(pin "1"
		)
		(instances
			(project "data-center-rdimm-ddr5-tester"
				(path ""
					(reference "#PWR061")
					(unit 1)
				)
			)
		)
	)
	(symbol
		(lib_id "antmicropower:GND")
		(at 163.83 241.3 0)
		(unit 1)
		(exclude_from_sim no)
		(in_bom yes)
		(on_board yes)
		(dnp no)
		(fields_autoplaced yes)
		(property "Reference" "#PWR084"
			(at 163.83 247.65 0)
			(effects
				(font
					(size 1.27 1.27)
				)
				(hide yes)
			)
		)
		(property "Value" "GND"
			(at 161.925 245.745 0)
			(effects
				(font
					(size 1.27 1.27)
					(thickness 0.15)
				)
				(justify left bottom)
			)
		)
		(property "Footprint" ""
			(at 172.72 248.92 0)
			(effects
				(font
					(size 1.27 1.27)
					(thickness 0.15)
				)
				(justify left bottom)
				(hide yes)
			)
		)
		(property "Datasheet" ""
			(at 172.72 254 0)
			(effects
				(font
					(size 1.27 1.27)
					(thickness 0.15)
				)
				(justify left bottom)
				(hide yes)
			)
		)
		(property "Description" ""
			(at 163.83 241.3 0)
			(effects
				(font
					(size 1.27 1.27)
				)
				(hide yes)
			)
		)
		(property "Author" "Antmicro"
			(at 172.72 246.38 0)
			(effects
				(font
					(size 1.27 1.27)
					(thickness 0.15)
				)
				(justify left bottom)
				(hide yes)
			)
		)
		(property "License" "Apache-2.0"
			(at 172.72 248.92 0)
			(effects
				(font
					(size 1.27 1.27)
					(thickness 0.15)
				)
				(justify left bottom)
				(hide yes)
			)
		)
		(pin "1"
		)
		(instances
			(project "data-center-rdimm-ddr5-tester"
				(path ""
					(reference "#PWR084")
					(unit 1)
				)
			)
		)
	)
	(symbol
		(lib_id "antmicropower:GND")
		(at 111.76 120.65 0)
		(unit 1)
		(exclude_from_sim no)
		(in_bom yes)
		(on_board yes)
		(dnp no)
		(fields_autoplaced yes)
		(property "Reference" "#PWR0118"
			(at 111.76 127 0)
			(effects
				(font
					(size 1.27 1.27)
				)
				(hide yes)
			)
		)
		(property "Value" "GND"
			(at 109.855 125.095 0)
			(effects
				(font
					(size 1.27 1.27)
					(thickness 0.15)
				)
				(justify left bottom)
			)
		)
		(property "Footprint" ""
			(at 120.65 128.27 0)
			(effects
				(font
					(size 1.27 1.27)
					(thickness 0.15)
				)
				(justify left bottom)
				(hide yes)
			)
		)
		(property "Datasheet" ""
			(at 120.65 133.35 0)
			(effects
				(font
					(size 1.27 1.27)
					(thickness 0.15)
				)
				(justify left bottom)
				(hide yes)
			)
		)
		(property "Description" ""
			(at 111.76 120.65 0)
			(effects
				(font
					(size 1.27 1.27)
				)
				(hide yes)
			)
		)
		(property "Author" "Antmicro"
			(at 120.65 125.73 0)
			(effects
				(font
					(size 1.27 1.27)
					(thickness 0.15)
				)
				(justify left bottom)
				(hide yes)
			)
		)
		(property "License" "Apache-2.0"
			(at 120.65 128.27 0)
			(effects
				(font
					(size 1.27 1.27)
					(thickness 0.15)
				)
				(justify left bottom)
				(hide yes)
			)
		)
		(pin "1"
		)
		(instances
			(project "data-center-rdimm-ddr5-tester"
				(path ""
					(reference "#PWR0118")
					(unit 1)
				)
			)
		)
	)
	(symbol
		(lib_id "antmicropower:GND")
		(at 356.87 134.62 0)
		(unit 1)
		(exclude_from_sim no)
		(in_bom yes)
		(on_board yes)
		(dnp no)
		(fields_autoplaced yes)
		(property "Reference" "#PWR0155"
			(at 356.87 140.97 0)
			(effects
				(font
					(size 1.27 1.27)
				)
				(hide yes)
			)
		)
		(property "Value" "GND"
			(at 354.965 139.065 0)
			(effects
				(font
					(size 1.27 1.27)
					(thickness 0.15)
				)
				(justify left bottom)
			)
		)
		(property "Footprint" ""
			(at 365.76 142.24 0)
			(effects
				(font
					(size 1.27 1.27)
					(thickness 0.15)
				)
				(justify left bottom)
				(hide yes)
			)
		)
		(property "Datasheet" ""
			(at 365.76 147.32 0)
			(effects
				(font
					(size 1.27 1.27)
					(thickness 0.15)
				)
				(justify left bottom)
				(hide yes)
			)
		)
		(property "Description" ""
			(at 356.87 134.62 0)
			(effects
				(font
					(size 1.27 1.27)
				)
				(hide yes)
			)
		)
		(property "Author" "Antmicro"
			(at 365.76 139.7 0)
			(effects
				(font
					(size 1.27 1.27)
					(thickness 0.15)
				)
				(justify left bottom)
				(hide yes)
			)
		)
		(property "License" "Apache-2.0"
			(at 365.76 142.24 0)
			(effects
				(font
					(size 1.27 1.27)
					(thickness 0.15)
				)
				(justify left bottom)
				(hide yes)
			)
		)
		(pin "1"
		)
		(instances
			(project "data-center-rdimm-ddr5-tester"
				(path ""
					(reference "#PWR0155")
					(unit 1)
				)
			)
		)
	)
	(symbol
		(lib_id "antmicroFPGAChips:XCAU25P-2FFVB676I")
		(at 223.52 111.76 0)
		(mirror y)
		(unit 12)
		(exclude_from_sim no)
		(in_bom yes)
		(on_board yes)
		(dnp no)
		(property "Reference" "U34"
			(at 203.2 104.14 0)
			(effects
				(font
					(size 1.27 1.27)
					(thickness 0.15)
				)
			)
		)
		(property "Value" "XCAU25P-2FFVB676I"
			(at 160.02 116.84 0)
			(effects
				(font
					(size 1.27 1.27)
					(thickness 0.15)
				)
				(justify left bottom)
				(hide yes)
			)
		)
		(property "Footprint" "antmicro-footprints:BGA-676_27x27mm_Layout26x26_P1x1mm_FFVB676"
			(at 160.02 119.38 0)
			(effects
				(font
					(size 1.27 1.27)
					(thickness 0.15)
				)
				(justify left bottom)
				(hide yes)
			)
		)
		(property "Datasheet" "https://docs.xilinx.com/viewer/book-attachment/2PXOpPtpaABIt0fkzeBLnw/hvbsEUaOT0OxFhln7VEVyA"
			(at 160.02 121.92 0)
			(effects
				(font
					(size 1.27 1.27)
					(thickness 0.15)
				)
				(justify left bottom)
				(hide yes)
			)
		)
		(property "Description" ""
			(at 223.52 111.76 0)
			(effects
				(font
					(size 1.27 1.27)
				)
				(hide yes)
			)
		)
		(property "MPN" "XCAU25P-2FFVB676I"
			(at 203.2 106.68 0)
			(effects
				(font
					(size 1.27 1.27)
					(thickness 0.15)
				)
			)
		)
		(property "Manufacturer" "AMD-Xilinx"
			(at 160.02 124.46 0)
			(effects
				(font
					(size 1.27 1.27)
					(thickness 0.15)
				)
				(justify left bottom)
				(hide yes)
			)
		)
		(property "Author" "Antmicro"
			(at 160.02 127 0)
			(effects
				(font
					(size 1.27 1.27)
					(thickness 0.15)
				)
				(justify left bottom)
				(hide yes)
			)
		)
		(property "License" "Apache-2.0"
			(at 160.02 129.54 0)
			(effects
				(font
					(size 1.27 1.27)
					(thickness 0.15)
				)
				(justify left bottom)
				(hide yes)
			)
		)
		(pin "AC23"
		)
		(pin "P20"
		)
		(pin "N19"
		)
		(pin "AA24"
		)
		(pin "J16"
		)
		(pin "J21"
		)
		(pin "AE10"
		)
		(pin "F6"
		)
		(pin "F7"
		)
		(pin "AF17"
		)
		(pin "AA15"
		)
		(pin "J25"
		)
		(pin "Y21"
		)
		(pin "AA7"
		)
		(pin "E26"
		)
		(pin "AD16"
		)
		(pin "V1"
		)
		(pin "AB14"
		)
		(pin "Y1"
		)
		(pin "E24"
		)
		(pin "AA14"
		)
		(pin "J20"
		)
		(pin "U25"
		)
		(pin "AE18"
		)
		(pin "U22"
		)
		(pin "P4"
		)
		(pin "P5"
		)
		(pin "R1"
		)
		(pin "R10"
		)
		(pin "P8"
		)
		(pin "P9"
		)
		(pin "R11"
		)
		(pin "R12"
		)
		(pin "AD3"
		)
		(pin "AD9"
		)
		(pin "AD4"
		)
		(pin "P18"
		)
		(pin "P3"
		)
		(pin "G14"
		)
		(pin "AE26"
		)
		(pin "B12"
		)
		(pin "AC2"
		)
		(pin "W7"
		)
		(pin "W8"
		)
		(pin "W11"
		)
		(pin "W17"
		)
		(pin "W2"
		)
		(pin "W22"
		)
		(pin "W3"
		)
		(pin "W6"
		)
		(pin "P6"
		)
		(pin "U26"
		)
		(pin "P19"
		)
		(pin "U1"
		)
		(pin "U10"
		)
		(pin "J15"
		)
		(pin "AB25"
		)
		(pin "L23"
		)
		(pin "P24"
		)
		(pin "G16"
		)
		(pin "C10"
		)
		(pin "F14"
		)
		(pin "U24"
		)
		(pin "Y24"
		)
		(pin "Y11"
		)
		(pin "J26"
		)
		(pin "AB4"
		)
		(pin "AD18"
		)
		(pin "J24"
		)
		(pin "AF2"
		)
		(pin "B26"
		)
		(pin "U6"
		)
		(pin "U7"
		)
		(pin "M11"
		)
		(pin "M12"
		)
		(pin "T20"
		)
		(pin "V23"
		)
		(pin "AD10"
		)
		(pin "D1"
		)
		(pin "AF1"
		)
		(pin "C8"
		)
		(pin "U13"
		)
		(pin "U14"
		)
		(pin "AD19"
		)
		(pin "Y4"
		)
		(pin "Y5"
		)
		(pin "E23"
		)
		(pin "C6"
		)
		(pin "AE14"
		)
		(pin "D22"
		)
		(pin "C20"
		)
		(pin "AB17"
		)
		(pin "AD24"
		)
		(pin "L1"
		)
		(pin "L10"
		)
		(pin "AE3"
		)
		(pin "G21"
		)
		(pin "AA17"
		)
		(pin "D6"
		)
		(pin "M25"
		)
		(pin "R17"
		)
		(pin "R18"
		)
		(pin "AE15"
		)
		(pin "H7"
		)
		(pin "H8"
		)
		(pin "R6"
		)
		(pin "R7"
		)
		(pin "AB20"
		)
		(pin "C5"
		)
		(pin "Y14"
		)
		(pin "AE13"
		)
		(pin "C13"
		)
		(pin "W4"
		)
		(pin "P22"
		)
		(pin "AF6"
		)
		(pin "B8"
		)
		(pin "AF18"
		)
		(pin "G22"
		)
		(pin "J2"
		)
		(pin "J3"
		)
		(pin "L3"
		)
		(pin "L6"
		)
		(pin "P12"
		)
		(pin "P15"
		)
		(pin "Y12"
		)
		(pin "K18"
		)
		(pin "V10"
		)
		(pin "V11"
		)
		(pin "D7"
		)
		(pin "D8"
		)
		(pin "P23"
		)
		(pin "AA3"
		)
		(pin "AB18"
		)
		(pin "H18"
		)
		(pin "B6"
		)
		(pin "R24"
		)
		(pin "R3"
		)
		(pin "P16"
		)
		(pin "P17"
		)
		(pin "AF23"
		)
		(pin "AC14"
		)
		(pin "M6"
		)
		(pin "B18"
		)
		(pin "M1"
		)
		(pin "B5"
		)
		(pin "D2"
		)
		(pin "G20"
		)
		(pin "M2"
		)
		(pin "B4"
		)
		(pin "AA16"
		)
		(pin "V9"
		)
		(pin "W1"
		)
		(pin "N5"
		)
		(pin "AA26"
		)
		(pin "B3"
		)
		(pin "D12"
		)
		(pin "N4"
		)
		(pin "AA2"
		)
		(pin "B23"
		)
		(pin "C12"
		)
		(pin "L5"
		)
		(pin "AA6"
		)
		(pin "B1"
		)
		(pin "H1"
		)
		(pin "A14"
		)
		(pin "A13"
		)
		(pin "AB2"
		)
		(pin "AE4"
		)
		(pin "Y16"
		)
		(pin "B24"
		)
		(pin "H16"
		)
		(pin "W24"
		)
		(pin "D18"
		)
		(pin "B20"
		)
		(pin "D21"
		)
		(pin "B19"
		)
		(pin "B25"
		)
		(pin "C24"
		)
		(pin "A15"
		)
		(pin "M26"
		)
		(pin "A23"
		)
		(pin "C17"
		)
		(pin "K21"
		)
		(pin "W23"
		)
		(pin "L24"
		)
		(pin "R20"
		)
		(pin "C21"
		)
		(pin "D24"
		)
		(pin "E15"
		)
		(pin "AD12"
		)
		(pin "D23"
		)
		(pin "D25"
		)
		(pin "C26"
		)
		(pin "B21"
		)
		(pin "Y26"
		)
		(pin "AE25"
		)
		(pin "C19"
		)
		(pin "C23"
		)
		(pin "P21"
		)
		(pin "A20"
		)
		(pin "L18"
		)
		(pin "A25"
		)
		(pin "K23"
		)
		(pin "V18"
		)
		(pin "C16"
		)
		(pin "V21"
		)
		(pin "E17"
		)
		(pin "A17"
		)
		(pin "P25"
		)
		(pin "AD25"
		)
		(pin "G18"
		)
		(pin "AB3"
		)
		(pin "J6"
		)
		(pin "J7"
		)
		(pin "K12"
		)
		(pin "K13"
		)
		(pin "AB16"
		)
		(pin "C1"
		)
		(pin "AF15"
		)
		(pin "J8"
		)
		(pin "K11"
		)
		(pin "AD1"
		)
		(pin "F25"
		)
		(pin "AE1"
		)
		(pin "V2"
		)
		(pin "U2"
		)
		(pin "U3"
		)
		(pin "F2"
		)
		(pin "V6"
		)
		(pin "P1"
		)
		(pin "L13"
		)
		(pin "L14"
		)
		(pin "AD5"
		)
		(pin "AE8"
		)
		(pin "AB10"
		)
		(pin "U15"
		)
		(pin "U16"
		)
		(pin "U17"
		)
		(pin "U18"
		)
		(pin "D26"
		)
		(pin "G5"
		)
		(pin "E25"
		)
		(pin "AD22"
		)
		(pin "A19"
		)
		(pin "P7"
		)
		(pin "Y2"
		)
		(pin "J22"
		)
		(pin "Y19"
		)
		(pin "Y3"
		)
		(pin "AB7"
		)
		(pin "AF22"
		)
		(pin "B2"
		)
		(pin "AA10"
		)
		(pin "V7"
		)
		(pin "V22"
		)
		(pin "J23"
		)
		(pin "AF12"
		)
		(pin "V16"
		)
		(pin "V17"
		)
		(pin "Y7"
		)
		(pin "D15"
		)
		(pin "H12"
		)
		(pin "AF7"
		)
		(pin "U23"
		)
		(pin "V19"
		)
		(pin "AF14"
		)
		(pin "AF13"
		)
		(pin "G8"
		)
		(pin "H20"
		)
		(pin "U11"
		)
		(pin "U12"
		)
		(pin "A5"
		)
		(pin "G6"
		)
		(pin "G7"
		)
		(pin "L15"
		)
		(pin "L16"
		)
		(pin "T8"
		)
		(pin "T9"
		)
		(pin "G19"
		)
		(pin "G17"
		)
		(pin "T4"
		)
		(pin "T5"
		)
		(pin "B13"
		)
		(pin "G23"
		)
		(pin "G3"
		)
		(pin "T26"
		)
		(pin "T3"
		)
		(pin "G13"
		)
		(pin "G2"
		)
		(pin "D17"
		)
		(pin "AD15"
		)
		(pin "Y8"
		)
		(pin "Y9"
		)
		(pin "AC24"
		)
		(pin "AD8"
		)
		(pin "F8"
		)
		(pin "G1"
		)
		(pin "AD6"
		)
		(pin "F18"
		)
		(pin "H17"
		)
		(pin "AA13"
		)
		(pin "K20"
		)
		(pin "AD7"
		)
		(pin "AA1"
		)
		(pin "AF19"
		)
		(pin "Y15"
		)
		(pin "AB13"
		)
		(pin "N13"
		)
		(pin "N14"
		)
		(pin "V14"
		)
		(pin "V15"
		)
		(pin "U8"
		)
		(pin "U9"
		)
		(pin "W13"
		)
		(pin "V5"
		)
		(pin "V8"
		)
		(pin "W5"
		)
		(pin "P26"
		)
		(pin "Y20"
		)
		(pin "L17"
		)
		(pin "L2"
		)
		(pin "H26"
		)
		(pin "Y6"
		)
		(pin "AC22"
		)
		(pin "D13"
		)
		(pin "V12"
		)
		(pin "V13"
		)
		(pin "AE9"
		)
		(pin "B7"
		)
		(pin "A11"
		)
		(pin "K9"
		)
		(pin "L11"
		)
		(pin "L12"
		)
		(pin "H5"
		)
		(pin "H6"
		)
		(pin "AE19"
		)
		(pin "C18"
		)
		(pin "H13"
		)
		(pin "AB23"
		)
		(pin "AC26"
		)
		(pin "R19"
		)
		(pin "R2"
		)
		(pin "H19"
		)
		(pin "AF20"
		)
		(pin "AF24"
		)
		(pin "B22"
		)
		(pin "B14"
		)
		(pin "D4"
		)
		(pin "AA18"
		)
		(pin "C22"
		)
		(pin "V24"
		)
		(pin "A12"
		)
		(pin "C7"
		)
		(pin "M7"
		)
		(pin "AB5"
		)
		(pin "W18"
		)
		(pin "T18"
		)
		(pin "T21"
		)
		(pin "F13"
		)
		(pin "D3"
		)
		(pin "F1"
		)
		(pin "L21"
		)
		(pin "L26"
		)
		(pin "AA11"
		)
		(pin "M20"
		)
		(pin "AC4"
		)
		(pin "AE5"
		)
		(pin "D19"
		)
		(pin "E10"
		)
		(pin "AA9"
		)
		(pin "Y22"
		)
		(pin "V3"
		)
		(pin "V4"
		)
		(pin "AD2"
		)
		(pin "AC10"
		)
		(pin "C25"
		)
		(pin "G4"
		)
		(pin "A6"
		)
		(pin "E6"
		)
		(pin "E7"
		)
		(pin "E1"
		)
		(pin "E19"
		)
		(pin "R4"
		)
		(pin "T10"
		)
		(pin "T11"
		)
		(pin "J10"
		)
		(pin "F17"
		)
		(pin "A24"
		)
		(pin "AC15"
		)
		(pin "C15"
		)
		(pin "A1"
		)
		(pin "J1"
		)
		(pin "J17"
		)
		(pin "AE6"
		)
		(pin "E4"
		)
		(pin "E5"
		)
		(pin "M23"
		)
		(pin "M3"
		)
		(pin "R22"
		)
		(pin "AA5"
		)
		(pin "AC12"
		)
		(pin "Y18"
		)
		(pin "W20"
		)
		(pin "AC21"
		)
		(pin "R23"
		)
		(pin "K10"
		)
		(pin "AC17"
		)
		(pin "AC20"
		)
		(pin "V20"
		)
		(pin "V25"
		)
		(pin "N1"
		)
		(pin "N10"
		)
		(pin "M4"
		)
		(pin "M5"
		)
		(pin "R25"
		)
		(pin "H3"
		)
		(pin "H4"
		)
		(pin "AD13"
		)
		(pin "AD17"
		)
		(pin "N26"
		)
		(pin "R13"
		)
		(pin "N6"
		)
		(pin "N7"
		)
		(pin "U4"
		)
		(pin "R5"
		)
		(pin "K3"
		)
		(pin "K4"
		)
		(pin "AF3"
		)
		(pin "J5"
		)
		(pin "P2"
		)
		(pin "N22"
		)
		(pin "T16"
		)
		(pin "T17"
		)
		(pin "C3"
		)
		(pin "AF4"
		)
		(pin "T13"
		)
		(pin "AA12"
		)
		(pin "AB26"
		)
		(pin "AF21"
		)
		(pin "N25"
		)
		(pin "N3"
		)
		(pin "N21"
		)
		(pin "J12"
		)
		(pin "A8"
		)
		(pin "W12"
		)
		(pin "H14"
		)
		(pin "U21"
		)
		(pin "W9"
		)
		(pin "T14"
		)
		(pin "AE23"
		)
		(pin "K19"
		)
		(pin "K24"
		)
		(pin "Y25"
		)
		(pin "G12"
		)
		(pin "N2"
		)
		(pin "N20"
		)
		(pin "T25"
		)
		(pin "AC8"
		)
		(pin "E16"
		)
		(pin "AC19"
		)
		(pin "C14"
		)
		(pin "F4"
		)
		(pin "F5"
		)
		(pin "U19"
		)
		(pin "AE12"
		)
		(pin "P14"
		)
		(pin "AF8"
		)
		(pin "AF9"
		)
		(pin "V26"
		)
		(pin "W19"
		)
		(pin "L4"
		)
		(pin "G24"
		)
		(pin "R15"
		)
		(pin "R16"
		)
		(pin "U5"
		)
		(pin "AC16"
		)
		(pin "AF25"
		)
		(pin "T7"
		)
		(pin "F24"
		)
		(pin "D16"
		)
		(pin "AA19"
		)
		(pin "D5"
		)
		(pin "L22"
		)
		(pin "B17"
		)
		(pin "H15"
		)
		(pin "AE21"
		)
		(pin "AE7"
		)
		(pin "K5"
		)
		(pin "K6"
		)
		(pin "T1"
		)
		(pin "AE22"
		)
		(pin "E22"
		)
		(pin "AF10"
		)
		(pin "AB6"
		)
		(pin "AD26"
		)
		(pin "AC13"
		)
		(pin "E18"
		)
		(pin "M15"
		)
		(pin "M16"
		)
		(pin "G15"
		)
		(pin "N8"
		)
		(pin "N9"
		)
		(pin "W26"
		)
		(pin "F20"
		)
		(pin "AD23"
		)
		(pin "AA8"
		)
		(pin "D20"
		)
		(pin "AF11"
		)
		(pin "E8"
		)
		(pin "F11"
		)
		(pin "AC5"
		)
		(pin "AA22"
		)
		(pin "E20"
		)
		(pin "W14"
		)
		(pin "M19"
		)
		(pin "H24"
		)
		(pin "K7"
		)
		(pin "K8"
		)
		(pin "C4"
		)
		(pin "H25"
		)
		(pin "W21"
		)
		(pin "P13"
		)
		(pin "L20"
		)
		(pin "AB21"
		)
		(pin "C2"
		)
		(pin "H22"
		)
		(pin "Y17"
		)
		(pin "AE11"
		)
		(pin "H2"
		)
		(pin "F23"
		)
		(pin "E11"
		)
		(pin "AB24"
		)
		(pin "AA4"
		)
		(pin "T6"
		)
		(pin "AD20"
		)
		(pin "A10"
		)
		(pin "C9"
		)
		(pin "W15"
		)
		(pin "E21"
		)
		(pin "AB22"
		)
		(pin "W16"
		)
		(pin "AC25"
		)
		(pin "T22"
		)
		(pin "K1"
		)
		(pin "AD14"
		)
		(pin "T2"
		)
		(pin "J19"
		)
		(pin "D9"
		)
		(pin "AE17"
		)
		(pin "AB1"
		)
		(pin "T24"
		)
		(pin "F9"
		)
		(pin "M8"
		)
		(pin "M9"
		)
		(pin "Y23"
		)
		(pin "AC7"
		)
		(pin "M13"
		)
		(pin "M14"
		)
		(pin "G25"
		)
		(pin "A9"
		)
		(pin "AB19"
		)
		(pin "A7"
		)
		(pin "N15"
		)
		(pin "N16"
		)
		(pin "Y13"
		)
		(pin "AF5"
		)
		(pin "R14"
		)
		(pin "AE20"
		)
		(pin "AB11"
		)
		(pin "W25"
		)
		(pin "T19"
		)
		(pin "H21"
		)
		(pin "K2"
		)
		(pin "T23"
		)
		(pin "AC6"
		)
		(pin "B15"
		)
		(pin "E9"
		)
		(pin "AC3"
		)
		(pin "F10"
		)
		(pin "A3"
		)
		(pin "F15"
		)
		(pin "U20"
		)
		(pin "G10"
		)
		(pin "N23"
		)
		(pin "AB15"
		)
		(pin "AA21"
		)
		(pin "P10"
		)
		(pin "P11"
		)
		(pin "J11"
		)
		(pin "Y10"
		)
		(pin "F19"
		)
		(pin "A22"
		)
		(pin "AE16"
		)
		(pin "F22"
		)
		(pin "G11"
		)
		(pin "K25"
		)
		(pin "B10"
		)
		(pin "AA20"
		)
		(pin "N24"
		)
		(pin "AA25"
		)
		(pin "E12"
		)
		(pin "D11"
		)
		(pin "E14"
		)
		(pin "AC1"
		)
		(pin "J4"
		)
		(pin "H11"
		)
		(pin "H9"
		)
		(pin "M22"
		)
		(pin "H10"
		)
		(pin "E13"
		)
		(pin "AD21"
		)
		(pin "D10"
		)
		(pin "B11"
		)
		(pin "G26"
		)
		(pin "L25"
		)
		(pin "AB9"
		)
		(pin "A2"
		)
		(pin "M21"
		)
		(pin "C11"
		)
		(pin "R21"
		)
		(pin "D14"
		)
		(pin "F12"
		)
		(pin "B9"
		)
		(pin "J9"
		)
		(pin "L19"
		)
		(pin "B16"
		)
		(pin "K22"
		)
		(pin "K26"
		)
		(pin "N11"
		)
		(pin "N12"
		)
		(pin "A16"
		)
		(pin "AB12"
		)
		(pin "L7"
		)
		(pin "L8"
		)
		(pin "AC11"
		)
		(pin "J18"
		)
		(pin "K16"
		)
		(pin "K17"
		)
		(pin "M24"
		)
		(pin "M17"
		)
		(pin "M18"
		)
		(pin "J14"
		)
		(pin "R8"
		)
		(pin "R9"
		)
		(pin "A26"
		)
		(pin "H23"
		)
		(pin "AF16"
		)
		(pin "F26"
		)
		(pin "F3"
		)
		(pin "AC18"
		)
		(pin "W10"
		)
		(pin "G9"
		)
		(pin "K14"
		)
		(pin "K15"
		)
		(pin "N17"
		)
		(pin "N18"
		)
		(pin "AC9"
		)
		(pin "J13"
		)
		(pin "AE24"
		)
		(pin "AA23"
		)
		(pin "E2"
		)
		(pin "E3"
		)
		(pin "AE2"
		)
		(pin "AF26"
		)
		(pin "A21"
		)
		(pin "L9"
		)
		(pin "M10"
		)
		(pin "F16"
		)
		(pin "F21"
		)
		(pin "R26"
		)
		(pin "T12"
		)
		(pin "T15"
		)
		(pin "AB8"
		)
		(pin "A18"
		)
		(pin "A4"
		)
		(pin "AD11"
		)
		(instances
			(project "data-center-rdimm-ddr5-tester"
				(path ""
					(reference "U34")
					(unit 12)
				)
			)
		)
	)
	(symbol
		(lib_id "antmicropower:GND")
		(at 276.86 273.05 0)
		(unit 1)
		(exclude_from_sim no)
		(in_bom yes)
		(on_board yes)
		(dnp no)
		(fields_autoplaced yes)
		(property "Reference" "#PWR069"
			(at 276.86 279.4 0)
			(effects
				(font
					(size 1.27 1.27)
				)
				(hide yes)
			)
		)
		(property "Value" "GND"
			(at 274.955 277.495 0)
			(effects
				(font
					(size 1.27 1.27)
					(thickness 0.15)
				)
				(justify left bottom)
			)
		)
		(property "Footprint" ""
			(at 285.75 280.67 0)
			(effects
				(font
					(size 1.27 1.27)
					(thickness 0.15)
				)
				(justify left bottom)
				(hide yes)
			)
		)
		(property "Datasheet" ""
			(at 285.75 285.75 0)
			(effects
				(font
					(size 1.27 1.27)
					(thickness 0.15)
				)
				(justify left bottom)
				(hide yes)
			)
		)
		(property "Description" ""
			(at 276.86 273.05 0)
			(effects
				(font
					(size 1.27 1.27)
				)
				(hide yes)
			)
		)
		(property "Author" "Antmicro"
			(at 285.75 278.13 0)
			(effects
				(font
					(size 1.27 1.27)
					(thickness 0.15)
				)
				(justify left bottom)
				(hide yes)
			)
		)
		(property "License" "Apache-2.0"
			(at 285.75 280.67 0)
			(effects
				(font
					(size 1.27 1.27)
					(thickness 0.15)
				)
				(justify left bottom)
				(hide yes)
			)
		)
		(pin "1"
		)
		(instances
			(project "data-center-rdimm-ddr5-tester"
				(path ""
					(reference "#PWR069")
					(unit 1)
				)
			)
		)
	)
	(symbol
		(lib_id "antmicroCapacitors0402:C_100n_0402")
		(at 355.6 173.99 90)
		(unit 1)
		(exclude_from_sim no)
		(in_bom yes)
		(on_board yes)
		(dnp no)
		(property "Reference" "C96"
			(at 356.235 169.545 90)
			(effects
				(font
					(size 1.27 1.27)
					(thickness 0.15)
				)
				(justify right)
			)
		)
		(property "Value" "C_100n_0402"
			(at 365.76 153.67 0)
			(effects
				(font
					(size 1.27 1.27)
					(thickness 0.15)
				)
				(justify left bottom)
				(hide yes)
			)
		)
		(property "Footprint" "antmicro-footprints:C_0402_1005Metric_EIA"
			(at 368.3 153.67 0)
			(effects
				(font
					(size 1.27 1.27)
					(thickness 0.15)
				)
				(justify left bottom)
				(hide yes)
			)
		)
		(property "Datasheet" "https://www.murata.com/products/productdetail?partno=GRM155R61H104KE14%23"
			(at 370.84 153.67 0)
			(effects
				(font
					(size 1.27 1.27)
					(thickness 0.15)
				)
				(justify left bottom)
				(hide yes)
			)
		)
		(property "Description" ""
			(at 355.6 173.99 0)
			(effects
				(font
					(size 1.27 1.27)
				)
				(hide yes)
			)
		)
		(property "MPN" "GRM155R61H104KE14D"
			(at 373.38 153.67 0)
			(effects
				(font
					(size 1.27 1.27)
					(thickness 0.15)
				)
				(justify left bottom)
				(hide yes)
			)
		)
		(property "Manufacturer" "Murata"
			(at 375.92 153.67 0)
			(effects
				(font
					(size 1.27 1.27)
					(thickness 0.15)
				)
				(justify left bottom)
				(hide yes)
			)
		)
		(property "License" "Apache-2.0"
			(at 378.46 153.67 0)
			(effects
				(font
					(size 1.27 1.27)
					(thickness 0.15)
				)
				(justify left bottom)
				(hide yes)
			)
		)
		(property "Author" "Antmicro"
			(at 381 153.67 0)
			(effects
				(font
					(size 1.27 1.27)
					(thickness 0.15)
				)
				(justify left bottom)
				(hide yes)
			)
		)
		(property "Val" "100n"
			(at 356.235 173.355 90)
			(effects
				(font
					(size 1.27 1.27)
					(thickness 0.15)
				)
				(justify right)
			)
		)
		(property "Voltage" "50V"
			(at 383.54 153.67 0)
			(effects
				(font
					(size 1.27 1.27)
				)
				(justify left bottom)
				(hide yes)
			)
		)
		(property "Dielectric" "X5R"
			(at 386.08 153.67 0)
			(effects
				(font
					(size 1.27 1.27)
				)
				(justify left bottom)
				(hide yes)
			)
		)
		(pin "1"
		)
		(pin "2"
		)
		(instances
			(project "data-center-rdimm-ddr5-tester"
				(path ""
					(reference "C96")
					(unit 1)
				)
			)
		)
	)
	(symbol
		(lib_id "antmicropower:GND")
		(at 87.63 120.65 0)
		(unit 1)
		(exclude_from_sim no)
		(in_bom yes)
		(on_board yes)
		(dnp no)
		(fields_autoplaced yes)
		(property "Reference" "#PWR0102"
			(at 87.63 127 0)
			(effects
				(font
					(size 1.27 1.27)
				)
				(hide yes)
			)
		)
		(property "Value" "GND"
			(at 85.725 125.095 0)
			(effects
				(font
					(size 1.27 1.27)
					(thickness 0.15)
				)
				(justify left bottom)
			)
		)
		(property "Footprint" ""
			(at 96.52 128.27 0)
			(effects
				(font
					(size 1.27 1.27)
					(thickness 0.15)
				)
				(justify left bottom)
				(hide yes)
			)
		)
		(property "Datasheet" ""
			(at 96.52 133.35 0)
			(effects
				(font
					(size 1.27 1.27)
					(thickness 0.15)
				)
				(justify left bottom)
				(hide yes)
			)
		)
		(property "Description" ""
			(at 87.63 120.65 0)
			(effects
				(font
					(size 1.27 1.27)
				)
				(hide yes)
			)
		)
		(property "Author" "Antmicro"
			(at 96.52 125.73 0)
			(effects
				(font
					(size 1.27 1.27)
					(thickness 0.15)
				)
				(justify left bottom)
				(hide yes)
			)
		)
		(property "License" "Apache-2.0"
			(at 96.52 128.27 0)
			(effects
				(font
					(size 1.27 1.27)
					(thickness 0.15)
				)
				(justify left bottom)
				(hide yes)
			)
		)
		(pin "1"
		)
		(instances
			(project "data-center-rdimm-ddr5-tester"
				(path ""
					(reference "#PWR0102")
					(unit 1)
				)
			)
		)
	)
	(symbol
		(lib_id "antmicropower:GND")
		(at 205.74 241.3 0)
		(unit 1)
		(exclude_from_sim no)
		(in_bom yes)
		(on_board yes)
		(dnp no)
		(fields_autoplaced yes)
		(property "Reference" "#PWR0108"
			(at 205.74 247.65 0)
			(effects
				(font
					(size 1.27 1.27)
				)
				(hide yes)
			)
		)
		(property "Value" "GND"
			(at 203.835 245.745 0)
			(effects
				(font
					(size 1.27 1.27)
					(thickness 0.15)
				)
				(justify left bottom)
			)
		)
		(property "Footprint" ""
			(at 214.63 248.92 0)
			(effects
				(font
					(size 1.27 1.27)
					(thickness 0.15)
				)
				(justify left bottom)
				(hide yes)
			)
		)
		(property "Datasheet" ""
			(at 214.63 254 0)
			(effects
				(font
					(size 1.27 1.27)
					(thickness 0.15)
				)
				(justify left bottom)
				(hide yes)
			)
		)
		(property "Description" ""
			(at 205.74 241.3 0)
			(effects
				(font
					(size 1.27 1.27)
				)
				(hide yes)
			)
		)
		(property "Author" "Antmicro"
			(at 214.63 246.38 0)
			(effects
				(font
					(size 1.27 1.27)
					(thickness 0.15)
				)
				(justify left bottom)
				(hide yes)
			)
		)
		(property "License" "Apache-2.0"
			(at 214.63 248.92 0)
			(effects
				(font
					(size 1.27 1.27)
					(thickness 0.15)
				)
				(justify left bottom)
				(hide yes)
			)
		)
		(pin "1"
		)
		(instances
			(project "data-center-rdimm-ddr5-tester"
				(path ""
					(reference "#PWR0108")
					(unit 1)
				)
			)
		)
	)
	(symbol
		(lib_id "antmicropower:GND")
		(at 53.34 148.59 0)
		(unit 1)
		(exclude_from_sim no)
		(in_bom yes)
		(on_board yes)
		(dnp no)
		(fields_autoplaced yes)
		(property "Reference" "#PWR083"
			(at 53.34 154.94 0)
			(effects
				(font
					(size 1.27 1.27)
				)
				(hide yes)
			)
		)
		(property "Value" "GND"
			(at 51.435 153.035 0)
			(effects
				(font
					(size 1.27 1.27)
					(thickness 0.15)
				)
				(justify left bottom)
			)
		)
		(property "Footprint" ""
			(at 62.23 156.21 0)
			(effects
				(font
					(size 1.27 1.27)
					(thickness 0.15)
				)
				(justify left bottom)
				(hide yes)
			)
		)
		(property "Datasheet" ""
			(at 62.23 161.29 0)
			(effects
				(font
					(size 1.27 1.27)
					(thickness 0.15)
				)
				(justify left bottom)
				(hide yes)
			)
		)
		(property "Description" ""
			(at 53.34 148.59 0)
			(effects
				(font
					(size 1.27 1.27)
				)
				(hide yes)
			)
		)
		(property "Author" "Antmicro"
			(at 62.23 153.67 0)
			(effects
				(font
					(size 1.27 1.27)
					(thickness 0.15)
				)
				(justify left bottom)
				(hide yes)
			)
		)
		(property "License" "Apache-2.0"
			(at 62.23 156.21 0)
			(effects
				(font
					(size 1.27 1.27)
					(thickness 0.15)
				)
				(justify left bottom)
				(hide yes)
			)
		)
		(pin "1"
		)
		(instances
			(project "data-center-rdimm-ddr5-tester"
				(path ""
					(reference "#PWR083")
					(unit 1)
				)
			)
		)
	)
	(symbol
		(lib_id "antmicropower:GND")
		(at 95.25 173.99 0)
		(unit 1)
		(exclude_from_sim no)
		(in_bom yes)
		(on_board yes)
		(dnp no)
		(fields_autoplaced yes)
		(property "Reference" "#PWR0106"
			(at 95.25 180.34 0)
			(effects
				(font
					(size 1.27 1.27)
				)
				(hide yes)
			)
		)
		(property "Value" "GND"
			(at 93.345 178.435 0)
			(effects
				(font
					(size 1.27 1.27)
					(thickness 0.15)
				)
				(justify left bottom)
			)
		)
		(property "Footprint" ""
			(at 104.14 181.61 0)
			(effects
				(font
					(size 1.27 1.27)
					(thickness 0.15)
				)
				(justify left bottom)
				(hide yes)
			)
		)
		(property "Datasheet" ""
			(at 104.14 186.69 0)
			(effects
				(font
					(size 1.27 1.27)
					(thickness 0.15)
				)
				(justify left bottom)
				(hide yes)
			)
		)
		(property "Description" ""
			(at 95.25 173.99 0)
			(effects
				(font
					(size 1.27 1.27)
				)
				(hide yes)
			)
		)
		(property "Author" "Antmicro"
			(at 104.14 179.07 0)
			(effects
				(font
					(size 1.27 1.27)
					(thickness 0.15)
				)
				(justify left bottom)
				(hide yes)
			)
		)
		(property "License" "Apache-2.0"
			(at 104.14 181.61 0)
			(effects
				(font
					(size 1.27 1.27)
					(thickness 0.15)
				)
				(justify left bottom)
				(hide yes)
			)
		)
		(pin "1"
		)
		(instances
			(project "data-center-rdimm-ddr5-tester"
				(path ""
					(reference "#PWR0106")
					(unit 1)
				)
			)
		)
	)
	(symbol
		(lib_id "antmicroCapacitors0402:C_100n_0402")
		(at 270.51 238.76 90)
		(unit 1)
		(exclude_from_sim no)
		(in_bom yes)
		(on_board yes)
		(dnp no)
		(property "Reference" "C89"
			(at 274.955 234.315 90)
			(effects
				(font
					(size 1.27 1.27)
					(thickness 0.15)
				)
				(justify left)
			)
		)
		(property "Value" "C_100n_0402"
			(at 280.67 218.44 0)
			(effects
				(font
					(size 1.27 1.27)
					(thickness 0.15)
				)
				(justify left bottom)
				(hide yes)
			)
		)
		(property "Footprint" "antmicro-footprints:C_0402_1005Metric_EIA"
			(at 283.21 218.44 0)
			(effects
				(font
					(size 1.27 1.27)
					(thickness 0.15)
				)
				(justify left bottom)
				(hide yes)
			)
		)
		(property "Datasheet" "https://www.murata.com/products/productdetail?partno=GRM155R61H104KE14%23"
			(at 285.75 218.44 0)
			(effects
				(font
					(size 1.27 1.27)
					(thickness 0.15)
				)
				(justify left bottom)
				(hide yes)
			)
		)
		(property "Description" ""
			(at 270.51 238.76 0)
			(effects
				(font
					(size 1.27 1.27)
				)
				(hide yes)
			)
		)
		(property "MPN" "GRM155R61H104KE14D"
			(at 288.29 218.44 0)
			(effects
				(font
					(size 1.27 1.27)
					(thickness 0.15)
				)
				(justify left bottom)
				(hide yes)
			)
		)
		(property "Manufacturer" "Murata"
			(at 290.83 218.44 0)
			(effects
				(font
					(size 1.27 1.27)
					(thickness 0.15)
				)
				(justify left bottom)
				(hide yes)
			)
		)
		(property "License" "Apache-2.0"
			(at 293.37 218.44 0)
			(effects
				(font
					(size 1.27 1.27)
					(thickness 0.15)
				)
				(justify left bottom)
				(hide yes)
			)
		)
		(property "Author" "Antmicro"
			(at 295.91 218.44 0)
			(effects
				(font
					(size 1.27 1.27)
					(thickness 0.15)
				)
				(justify left bottom)
				(hide yes)
			)
		)
		(property "Val" "100n"
			(at 276.225 238.125 90)
			(effects
				(font
					(size 1.27 1.27)
					(thickness 0.15)
				)
				(justify left)
			)
		)
		(property "Voltage" "50V"
			(at 298.45 218.44 0)
			(effects
				(font
					(size 1.27 1.27)
				)
				(justify left bottom)
				(hide yes)
			)
		)
		(property "Dielectric" "X5R"
			(at 300.99 218.44 0)
			(effects
				(font
					(size 1.27 1.27)
				)
				(justify left bottom)
				(hide yes)
			)
		)
		(pin "1"
		)
		(pin "2"
		)
		(instances
			(project "data-center-rdimm-ddr5-tester"
				(path ""
					(reference "C89")
					(unit 1)
				)
			)
		)
	)
	(symbol
		(lib_id "antmicropower:GND")
		(at 191.77 241.3 0)
		(unit 1)
		(exclude_from_sim no)
		(in_bom yes)
		(on_board yes)
		(dnp no)
		(fields_autoplaced yes)
		(property "Reference" "#PWR096"
			(at 191.77 247.65 0)
			(effects
				(font
					(size 1.27 1.27)
				)
				(hide yes)
			)
		)
		(property "Value" "GND"
			(at 189.865 245.745 0)
			(effects
				(font
					(size 1.27 1.27)
					(thickness 0.15)
				)
				(justify left bottom)
			)
		)
		(property "Footprint" ""
			(at 200.66 248.92 0)
			(effects
				(font
					(size 1.27 1.27)
					(thickness 0.15)
				)
				(justify left bottom)
				(hide yes)
			)
		)
		(property "Datasheet" ""
			(at 200.66 254 0)
			(effects
				(font
					(size 1.27 1.27)
					(thickness 0.15)
				)
				(justify left bottom)
				(hide yes)
			)
		)
		(property "Description" ""
			(at 191.77 241.3 0)
			(effects
				(font
					(size 1.27 1.27)
				)
				(hide yes)
			)
		)
		(property "Author" "Antmicro"
			(at 200.66 246.38 0)
			(effects
				(font
					(size 1.27 1.27)
					(thickness 0.15)
				)
				(justify left bottom)
				(hide yes)
			)
		)
		(property "License" "Apache-2.0"
			(at 200.66 248.92 0)
			(effects
				(font
					(size 1.27 1.27)
					(thickness 0.15)
				)
				(justify left bottom)
				(hide yes)
			)
		)
		(pin "1"
		)
		(instances
			(project "data-center-rdimm-ddr5-tester"
				(path ""
					(reference "#PWR096")
					(unit 1)
				)
			)
		)
	)
	(symbol
		(lib_id "antmicropower:GND")
		(at 361.95 66.04 0)
		(unit 1)
		(exclude_from_sim no)
		(in_bom yes)
		(on_board yes)
		(dnp no)
		(fields_autoplaced yes)
		(property "Reference" "#PWR0166"
			(at 361.95 72.39 0)
			(effects
				(font
					(size 1.27 1.27)
				)
				(hide yes)
			)
		)
		(property "Value" "GND"
			(at 360.045 70.485 0)
			(effects
				(font
					(size 1.27 1.27)
					(thickness 0.15)
				)
				(justify left bottom)
			)
		)
		(property "Footprint" ""
			(at 370.84 73.66 0)
			(effects
				(font
					(size 1.27 1.27)
					(thickness 0.15)
				)
				(justify left bottom)
				(hide yes)
			)
		)
		(property "Datasheet" ""
			(at 370.84 78.74 0)
			(effects
				(font
					(size 1.27 1.27)
					(thickness 0.15)
				)
				(justify left bottom)
				(hide yes)
			)
		)
		(property "Description" ""
			(at 361.95 66.04 0)
			(effects
				(font
					(size 1.27 1.27)
				)
				(hide yes)
			)
		)
		(property "Author" "Antmicro"
			(at 370.84 71.12 0)
			(effects
				(font
					(size 1.27 1.27)
					(thickness 0.15)
				)
				(justify left bottom)
				(hide yes)
			)
		)
		(property "License" "Apache-2.0"
			(at 370.84 73.66 0)
			(effects
				(font
					(size 1.27 1.27)
					(thickness 0.15)
				)
				(justify left bottom)
				(hide yes)
			)
		)
		(pin "1"
		)
		(instances
			(project "data-center-rdimm-ddr5-tester"
				(path ""
					(reference "#PWR0166")
					(unit 1)
				)
			)
		)
	)
	(symbol
		(lib_id "antmicropower:GND")
		(at 50.8 242.57 0)
		(unit 1)
		(exclude_from_sim no)
		(in_bom yes)
		(on_board yes)
		(dnp no)
		(fields_autoplaced yes)
		(property "Reference" "#PWR0112"
			(at 50.8 248.92 0)
			(effects
				(font
					(size 1.27 1.27)
				)
				(hide yes)
			)
		)
		(property "Value" "GND"
			(at 48.895 247.015 0)
			(effects
				(font
					(size 1.27 1.27)
					(thickness 0.15)
				)
				(justify left bottom)
			)
		)
		(property "Footprint" ""
			(at 59.69 250.19 0)
			(effects
				(font
					(size 1.27 1.27)
					(thickness 0.15)
				)
				(justify left bottom)
				(hide yes)
			)
		)
		(property "Datasheet" ""
			(at 59.69 255.27 0)
			(effects
				(font
					(size 1.27 1.27)
					(thickness 0.15)
				)
				(justify left bottom)
				(hide yes)
			)
		)
		(property "Description" ""
			(at 50.8 242.57 0)
			(effects
				(font
					(size 1.27 1.27)
				)
				(hide yes)
			)
		)
		(property "Author" "Antmicro"
			(at 59.69 247.65 0)
			(effects
				(font
					(size 1.27 1.27)
					(thickness 0.15)
				)
				(justify left bottom)
				(hide yes)
			)
		)
		(property "License" "Apache-2.0"
			(at 59.69 250.19 0)
			(effects
				(font
					(size 1.27 1.27)
					(thickness 0.15)
				)
				(justify left bottom)
				(hide yes)
			)
		)
		(pin "1"
		)
		(instances
			(project "data-center-rdimm-ddr5-tester"
				(path ""
					(reference "#PWR0112")
					(unit 1)
				)
			)
		)
	)
	(symbol
		(lib_id "antmicropower:GND")
		(at 118.11 67.31 0)
		(mirror y)
		(unit 1)
		(exclude_from_sim no)
		(in_bom yes)
		(on_board yes)
		(dnp no)
		(fields_autoplaced yes)
		(property "Reference" "#PWR0149"
			(at 118.11 73.66 0)
			(effects
				(font
					(size 1.27 1.27)
				)
				(hide yes)
			)
		)
		(property "Value" "GND"
			(at 120.015 71.755 0)
			(effects
				(font
					(size 1.27 1.27)
					(thickness 0.15)
				)
				(justify left bottom)
			)
		)
		(property "Footprint" ""
			(at 109.22 74.93 0)
			(effects
				(font
					(size 1.27 1.27)
					(thickness 0.15)
				)
				(justify left bottom)
				(hide yes)
			)
		)
		(property "Datasheet" ""
			(at 109.22 80.01 0)
			(effects
				(font
					(size 1.27 1.27)
					(thickness 0.15)
				)
				(justify left bottom)
				(hide yes)
			)
		)
		(property "Description" ""
			(at 118.11 67.31 0)
			(effects
				(font
					(size 1.27 1.27)
				)
				(hide yes)
			)
		)
		(property "Author" "Antmicro"
			(at 109.22 72.39 0)
			(effects
				(font
					(size 1.27 1.27)
					(thickness 0.15)
				)
				(justify left bottom)
				(hide yes)
			)
		)
		(property "License" "Apache-2.0"
			(at 109.22 74.93 0)
			(effects
				(font
					(size 1.27 1.27)
					(thickness 0.15)
				)
				(justify left bottom)
				(hide yes)
			)
		)
		(pin "1"
		)
		(instances
			(project "data-center-rdimm-ddr5-tester"
				(path ""
					(reference "#PWR0149")
					(unit 1)
				)
			)
		)
	)
	(symbol
		(lib_id "antmicropower:GND")
		(at 69.85 198.12 0)
		(unit 1)
		(exclude_from_sim no)
		(in_bom yes)
		(on_board yes)
		(dnp no)
		(fields_autoplaced yes)
		(property "Reference" "#PWR0138"
			(at 69.85 204.47 0)
			(effects
				(font
					(size 1.27 1.27)
				)
				(hide yes)
			)
		)
		(property "Value" "GND"
			(at 67.945 202.565 0)
			(effects
				(font
					(size 1.27 1.27)
					(thickness 0.15)
				)
				(justify left bottom)
			)
		)
		(property "Footprint" ""
			(at 78.74 205.74 0)
			(effects
				(font
					(size 1.27 1.27)
					(thickness 0.15)
				)
				(justify left bottom)
				(hide yes)
			)
		)
		(property "Datasheet" ""
			(at 78.74 210.82 0)
			(effects
				(font
					(size 1.27 1.27)
					(thickness 0.15)
				)
				(justify left bottom)
				(hide yes)
			)
		)
		(property "Description" ""
			(at 69.85 198.12 0)
			(effects
				(font
					(size 1.27 1.27)
				)
				(hide yes)
			)
		)
		(property "Author" "Antmicro"
			(at 78.74 203.2 0)
			(effects
				(font
					(size 1.27 1.27)
					(thickness 0.15)
				)
				(justify left bottom)
				(hide yes)
			)
		)
		(property "License" "Apache-2.0"
			(at 78.74 205.74 0)
			(effects
				(font
					(size 1.27 1.27)
					(thickness 0.15)
				)
				(justify left bottom)
				(hide yes)
			)
		)
		(pin "1"
		)
		(instances
			(project "data-center-rdimm-ddr5-tester"
				(path ""
					(reference "#PWR0138")
					(unit 1)
				)
			)
		)
	)
	(symbol
		(lib_id "antmicropower:+1V8_MGTVCCAUX")
		(at 259.08 100.33 0)
		(unit 1)
		(exclude_from_sim no)
		(in_bom yes)
		(on_board yes)
		(dnp no)
		(fields_autoplaced yes)
		(property "Reference" "#PWR042"
			(at 259.08 104.14 0)
			(effects
				(font
					(size 1.27 1.27)
				)
				(hide yes)
			)
		)
		(property "Value" "+1V8_MGTVCCAUX"
			(at 259.08 95.25 0)
			(effects
				(font
					(size 1.27 1.27)
				)
			)
		)
		(property "Footprint" ""
			(at 259.08 100.33 0)
			(effects
				(font
					(size 1.27 1.27)
				)
				(hide yes)
			)
		)
		(property "Datasheet" ""
			(at 259.08 100.33 0)
			(effects
				(font
					(size 1.27 1.27)
				)
				(hide yes)
			)
		)
		(property "Description" ""
			(at 259.08 100.33 0)
			(effects
				(font
					(size 1.27 1.27)
				)
				(hide yes)
			)
		)
		(pin "1"
		)
		(instances
			(project "data-center-rdimm-ddr5-tester"
				(path ""
					(reference "#PWR042")
					(unit 1)
				)
			)
		)
	)
	(symbol
		(lib_id "antmicroCapacitors0402:C_100n_0402")
		(at 50.8 241.3 90)
		(unit 1)
		(exclude_from_sim no)
		(in_bom yes)
		(on_board yes)
		(dnp no)
		(property "Reference" "C68"
			(at 51.435 236.855 90)
			(effects
				(font
					(size 1.27 1.27)
					(thickness 0.15)
				)
				(justify right)
			)
		)
		(property "Value" "C_100n_0402"
			(at 60.96 220.98 0)
			(effects
				(font
					(size 1.27 1.27)
					(thickness 0.15)
				)
				(justify left bottom)
				(hide yes)
			)
		)
		(property "Footprint" "antmicro-footprints:C_0402_1005Metric_EIA"
			(at 63.5 220.98 0)
			(effects
				(font
					(size 1.27 1.27)
					(thickness 0.15)
				)
				(justify left bottom)
				(hide yes)
			)
		)
		(property "Datasheet" "https://www.murata.com/products/productdetail?partno=GRM155R61H104KE14%23"
			(at 66.04 220.98 0)
			(effects
				(font
					(size 1.27 1.27)
					(thickness 0.15)
				)
				(justify left bottom)
				(hide yes)
			)
		)
		(property "Description" ""
			(at 50.8 241.3 0)
			(effects
				(font
					(size 1.27 1.27)
				)
				(hide yes)
			)
		)
		(property "MPN" "GRM155R61H104KE14D"
			(at 68.58 220.98 0)
			(effects
				(font
					(size 1.27 1.27)
					(thickness 0.15)
				)
				(justify left bottom)
				(hide yes)
			)
		)
		(property "Manufacturer" "Murata"
			(at 71.12 220.98 0)
			(effects
				(font
					(size 1.27 1.27)
					(thickness 0.15)
				)
				(justify left bottom)
				(hide yes)
			)
		)
		(property "License" "Apache-2.0"
			(at 73.66 220.98 0)
			(effects
				(font
					(size 1.27 1.27)
					(thickness 0.15)
				)
				(justify left bottom)
				(hide yes)
			)
		)
		(property "Author" "Antmicro"
			(at 76.2 220.98 0)
			(effects
				(font
					(size 1.27 1.27)
					(thickness 0.15)
				)
				(justify left bottom)
				(hide yes)
			)
		)
		(property "Val" "100n"
			(at 51.435 240.665 90)
			(effects
				(font
					(size 1.27 1.27)
					(thickness 0.15)
				)
				(justify right)
			)
		)
		(property "Voltage" "50V"
			(at 78.74 220.98 0)
			(effects
				(font
					(size 1.27 1.27)
				)
				(justify left bottom)
				(hide yes)
			)
		)
		(property "Dielectric" "X5R"
			(at 81.28 220.98 0)
			(effects
				(font
					(size 1.27 1.27)
				)
				(justify left bottom)
				(hide yes)
			)
		)
		(pin "1"
		)
		(pin "2"
		)
		(instances
			(project "data-center-rdimm-ddr5-tester"
				(path ""
					(reference "C68")
					(unit 1)
				)
			)
		)
	)
	(symbol
		(lib_id "antmicroCapacitorsmisc:C_100u_0805")
		(at 99.06 66.04 90)
		(unit 1)
		(exclude_from_sim no)
		(in_bom yes)
		(on_board yes)
		(dnp no)
		(property "Reference" "C241"
			(at 101.6 62.23 90)
			(effects
				(font
					(size 1.27 1.27)
					(thickness 0.15)
				)
				(justify right)
			)
		)
		(property "Value" "C_100u_0805"
			(at 109.22 45.72 0)
			(effects
				(font
					(size 1.27 1.27)
					(thickness 0.15)
				)
				(justify left bottom)
				(hide yes)
			)
		)
		(property "Footprint" "antmicro-footprints:C_0805_2012Metric"
			(at 111.76 45.72 0)
			(effects
				(font
					(size 1.27 1.27)
					(thickness 0.15)
				)
				(justify left bottom)
				(hide yes)
			)
		)
		(property "Datasheet" "https://www.murata.com/products/productdetail?partno=GRM21BR60J107ME15%23"
			(at 114.3 45.72 0)
			(effects
				(font
					(size 1.27 1.27)
					(thickness 0.15)
				)
				(justify left bottom)
				(hide yes)
			)
		)
		(property "Description" ""
			(at 99.06 66.04 0)
			(effects
				(font
					(size 1.27 1.27)
				)
				(hide yes)
			)
		)
		(property "MPN" "GRM21BR60J107ME15L"
			(at 116.84 45.72 0)
			(effects
				(font
					(size 1.27 1.27)
					(thickness 0.15)
				)
				(justify left bottom)
				(hide yes)
			)
		)
		(property "Manufacturer" "Murata"
			(at 119.38 45.72 0)
			(effects
				(font
					(size 1.27 1.27)
					(thickness 0.15)
				)
				(justify left bottom)
				(hide yes)
			)
		)
		(property "License" "Apache-2.0"
			(at 121.92 45.72 0)
			(effects
				(font
					(size 1.27 1.27)
					(thickness 0.15)
				)
				(justify left bottom)
				(hide yes)
			)
		)
		(property "Author" "Antmicro"
			(at 124.46 45.72 0)
			(effects
				(font
					(size 1.27 1.27)
					(thickness 0.15)
				)
				(justify left bottom)
				(hide yes)
			)
		)
		(property "Val" "100u"
			(at 101.6 64.77 90)
			(effects
				(font
					(size 1.27 1.27)
					(thickness 0.15)
				)
				(justify right)
			)
		)
		(property "Voltage" ""
			(at 127 45.72 0)
			(effects
				(font
					(size 1.27 1.27)
				)
				(justify left bottom)
				(hide yes)
			)
		)
		(property "Dielectric" ""
			(at 129.54 45.72 0)
			(effects
				(font
					(size 1.27 1.27)
				)
				(justify left bottom)
				(hide yes)
			)
		)
		(property "Public" "False"
			(at 132.08 45.72 0)
			(effects
				(font
					(size 1.27 1.27)
				)
				(justify left bottom)
				(hide yes)
			)
		)
		(pin "1"
		)
		(pin "2"
		)
		(instances
			(project "data-center-rdimm-ddr5-tester"
				(path ""
					(reference "C241")
					(unit 1)
				)
			)
		)
	)
	(symbol
		(lib_id "antmicropower:+1V8")
		(at 173.99 100.33 0)
		(unit 1)
		(exclude_from_sim no)
		(in_bom yes)
		(on_board yes)
		(dnp no)
		(fields_autoplaced yes)
		(property "Reference" "#PWR030"
			(at 189.23 102.87 0)
			(effects
				(font
					(size 1.27 1.27)
					(thickness 0.15)
				)
				(justify left bottom)
				(hide yes)
			)
		)
		(property "Value" "+1V8"
			(at 173.99 95.885 0)
			(effects
				(font
					(size 1.27 1.27)
					(thickness 0.15)
				)
			)
		)
		(property "Footprint" ""
			(at 189.23 107.95 0)
			(effects
				(font
					(size 1.27 1.27)
					(thickness 0.15)
				)
				(justify left bottom)
				(hide yes)
			)
		)
		(property "Datasheet" ""
			(at 189.23 110.49 0)
			(effects
				(font
					(size 1.27 1.27)
					(thickness 0.15)
				)
				(justify left bottom)
				(hide yes)
			)
		)
		(property "Description" ""
			(at 173.99 100.33 0)
			(effects
				(font
					(size 1.27 1.27)
				)
				(hide yes)
			)
		)
		(property "Author" "Antmicro"
			(at 189.23 105.41 0)
			(effects
				(font
					(size 1.27 1.27)
					(thickness 0.15)
				)
				(justify left bottom)
				(hide yes)
			)
		)
		(property "License" "Apache-2.0"
			(at 189.23 107.95 0)
			(effects
				(font
					(size 1.27 1.27)
					(thickness 0.15)
				)
				(justify left bottom)
				(hide yes)
			)
		)
		(pin "1"
		)
		(instances
			(project "data-center-rdimm-ddr5-tester"
				(path ""
					(reference "#PWR030")
					(unit 1)
				)
			)
		)
	)
	(symbol
		(lib_id "antmicropower:GND")
		(at 69.85 148.59 0)
		(unit 1)
		(exclude_from_sim no)
		(in_bom yes)
		(on_board yes)
		(dnp no)
		(fields_autoplaced yes)
		(property "Reference" "#PWR087"
			(at 69.85 154.94 0)
			(effects
				(font
					(size 1.27 1.27)
				)
				(hide yes)
			)
		)
		(property "Value" "GND"
			(at 67.945 153.035 0)
			(effects
				(font
					(size 1.27 1.27)
					(thickness 0.15)
				)
				(justify left bottom)
			)
		)
		(property "Footprint" ""
			(at 78.74 156.21 0)
			(effects
				(font
					(size 1.27 1.27)
					(thickness 0.15)
				)
				(justify left bottom)
				(hide yes)
			)
		)
		(property "Datasheet" ""
			(at 78.74 161.29 0)
			(effects
				(font
					(size 1.27 1.27)
					(thickness 0.15)
				)
				(justify left bottom)
				(hide yes)
			)
		)
		(property "Description" ""
			(at 69.85 148.59 0)
			(effects
				(font
					(size 1.27 1.27)
				)
				(hide yes)
			)
		)
		(property "Author" "Antmicro"
			(at 78.74 153.67 0)
			(effects
				(font
					(size 1.27 1.27)
					(thickness 0.15)
				)
				(justify left bottom)
				(hide yes)
			)
		)
		(property "License" "Apache-2.0"
			(at 78.74 156.21 0)
			(effects
				(font
					(size 1.27 1.27)
					(thickness 0.15)
				)
				(justify left bottom)
				(hide yes)
			)
		)
		(pin "1"
		)
		(instances
			(project "data-center-rdimm-ddr5-tester"
				(path ""
					(reference "#PWR087")
					(unit 1)
				)
			)
		)
	)
	(symbol
		(lib_id "antmicropower:GND")
		(at 62.23 120.65 0)
		(unit 1)
		(exclude_from_sim no)
		(in_bom yes)
		(on_board yes)
		(dnp no)
		(fields_autoplaced yes)
		(property "Reference" "#PWR080"
			(at 62.23 127 0)
			(effects
				(font
					(size 1.27 1.27)
				)
				(hide yes)
			)
		)
		(property "Value" "GND"
			(at 60.325 125.095 0)
			(effects
				(font
					(size 1.27 1.27)
					(thickness 0.15)
				)
				(justify left bottom)
			)
		)
		(property "Footprint" ""
			(at 71.12 128.27 0)
			(effects
				(font
					(size 1.27 1.27)
					(thickness 0.15)
				)
				(justify left bottom)
				(hide yes)
			)
		)
		(property "Datasheet" ""
			(at 71.12 133.35 0)
			(effects
				(font
					(size 1.27 1.27)
					(thickness 0.15)
				)
				(justify left bottom)
				(hide yes)
			)
		)
		(property "Description" ""
			(at 62.23 120.65 0)
			(effects
				(font
					(size 1.27 1.27)
				)
				(hide yes)
			)
		)
		(property "Author" "Antmicro"
			(at 71.12 125.73 0)
			(effects
				(font
					(size 1.27 1.27)
					(thickness 0.15)
				)
				(justify left bottom)
				(hide yes)
			)
		)
		(property "License" "Apache-2.0"
			(at 71.12 128.27 0)
			(effects
				(font
					(size 1.27 1.27)
					(thickness 0.15)
				)
				(justify left bottom)
				(hide yes)
			)
		)
		(pin "1"
		)
		(instances
			(project "data-center-rdimm-ddr5-tester"
				(path ""
					(reference "#PWR080")
					(unit 1)
				)
			)
		)
	)
	(symbol
		(lib_id "antmicroCapacitors0402:C_1u_25V_0402")
		(at 86.36 172.72 90)
		(unit 1)
		(exclude_from_sim no)
		(in_bom yes)
		(on_board yes)
		(dnp no)
		(fields_autoplaced yes)
		(property "Reference" "C58"
			(at 88.9 168.9036 90)
			(effects
				(font
					(size 1.27 1.27)
					(thickness 0.15)
				)
				(justify right)
			)
		)
		(property "Value" "C_1u_25V_0402"
			(at 96.52 152.4 0)
			(effects
				(font
					(size 1.27 1.27)
					(thickness 0.15)
				)
				(justify left bottom)
				(hide yes)
			)
		)
		(property "Footprint" "antmicro-footprints:C_0402_1005Metric_EIA"
			(at 99.06 152.4 0)
			(effects
				(font
					(size 1.27 1.27)
					(thickness 0.15)
				)
				(justify left bottom)
				(hide yes)
			)
		)
		(property "Datasheet" "https://www.murata.com/products/productdetail?partno=GRM155R61E105KE11%23"
			(at 101.6 152.4 0)
			(effects
				(font
					(size 1.27 1.27)
					(thickness 0.15)
				)
				(justify left bottom)
				(hide yes)
			)
		)
		(property "Description" ""
			(at 86.36 172.72 0)
			(effects
				(font
					(size 1.27 1.27)
				)
				(hide yes)
			)
		)
		(property "MPN" "GRM155R61E105KE11J"
			(at 104.14 152.4 0)
			(effects
				(font
					(size 1.27 1.27)
					(thickness 0.15)
				)
				(justify left bottom)
				(hide yes)
			)
		)
		(property "Manufacturer" "Murata"
			(at 106.68 152.4 0)
			(effects
				(font
					(size 1.27 1.27)
					(thickness 0.15)
				)
				(justify left bottom)
				(hide yes)
			)
		)
		(property "License" "Apache-2.0"
			(at 109.22 152.4 0)
			(effects
				(font
					(size 1.27 1.27)
					(thickness 0.15)
				)
				(justify left bottom)
				(hide yes)
			)
		)
		(property "Author" "Antmicro"
			(at 111.76 152.4 0)
			(effects
				(font
					(size 1.27 1.27)
					(thickness 0.15)
				)
				(justify left bottom)
				(hide yes)
			)
		)
		(property "Val" "1u"
			(at 88.9 171.4436 90)
			(effects
				(font
					(size 1.27 1.27)
					(thickness 0.15)
				)
				(justify right)
			)
		)
		(property "Voltage" "25V"
			(at 114.3 152.4 0)
			(effects
				(font
					(size 1.27 1.27)
				)
				(justify left bottom)
				(hide yes)
			)
		)
		(property "Dielectric" "X5R"
			(at 116.84 152.4 0)
			(effects
				(font
					(size 1.27 1.27)
				)
				(justify left bottom)
				(hide yes)
			)
		)
		(pin "1"
		)
		(pin "2"
		)
		(instances
			(project "data-center-rdimm-ddr5-tester"
				(path ""
					(reference "C58")
					(unit 1)
				)
			)
		)
	)
	(symbol
		(lib_id "antmicropower:GND")
		(at 238.76 241.3 0)
		(unit 1)
		(exclude_from_sim no)
		(in_bom yes)
		(on_board yes)
		(dnp no)
		(fields_autoplaced yes)
		(property "Reference" "#PWR0131"
			(at 238.76 247.65 0)
			(effects
				(font
					(size 1.27 1.27)
				)
				(hide yes)
			)
		)
		(property "Value" "GND"
			(at 236.855 245.745 0)
			(effects
				(font
					(size 1.27 1.27)
					(thickness 0.15)
				)
				(justify left bottom)
			)
		)
		(property "Footprint" ""
			(at 247.65 248.92 0)
			(effects
				(font
					(size 1.27 1.27)
					(thickness 0.15)
				)
				(justify left bottom)
				(hide yes)
			)
		)
		(property "Datasheet" ""
			(at 247.65 254 0)
			(effects
				(font
					(size 1.27 1.27)
					(thickness 0.15)
				)
				(justify left bottom)
				(hide yes)
			)
		)
		(property "Description" ""
			(at 238.76 241.3 0)
			(effects
				(font
					(size 1.27 1.27)
				)
				(hide yes)
			)
		)
		(property "Author" "Antmicro"
			(at 247.65 246.38 0)
			(effects
				(font
					(size 1.27 1.27)
					(thickness 0.15)
				)
				(justify left bottom)
				(hide yes)
			)
		)
		(property "License" "Apache-2.0"
			(at 247.65 248.92 0)
			(effects
				(font
					(size 1.27 1.27)
					(thickness 0.15)
				)
				(justify left bottom)
				(hide yes)
			)
		)
		(pin "1"
		)
		(instances
			(project "data-center-rdimm-ddr5-tester"
				(path ""
					(reference "#PWR0131")
					(unit 1)
				)
			)
		)
	)
	(symbol
		(lib_id "antmicropower:VDD")
		(at 218.44 231.14 0)
		(unit 1)
		(exclude_from_sim no)
		(in_bom yes)
		(on_board yes)
		(dnp no)
		(fields_autoplaced yes)
		(property "Reference" "#PWR091"
			(at 218.44 234.95 0)
			(effects
				(font
					(size 1.27 1.27)
				)
				(hide yes)
			)
		)
		(property "Value" "VDDQ"
			(at 218.44 226.06 0)
			(effects
				(font
					(size 1.27 1.27)
				)
			)
		)
		(property "Footprint" ""
			(at 218.44 231.14 0)
			(effects
				(font
					(size 1.27 1.27)
				)
				(hide yes)
			)
		)
		(property "Datasheet" ""
			(at 218.44 231.14 0)
			(effects
				(font
					(size 1.27 1.27)
				)
				(hide yes)
			)
		)
		(property "Description" ""
			(at 218.44 231.14 0)
			(effects
				(font
					(size 1.27 1.27)
				)
				(hide yes)
			)
		)
		(pin "1"
		)
		(instances
			(project "data-center-rdimm-ddr5-tester"
				(path ""
					(reference "#PWR091")
					(unit 1)
				)
			)
		)
	)
	(symbol
		(lib_id "antmicroCapacitors0402:C_4u7_0402")
		(at 340.36 128.27 270)
		(unit 1)
		(exclude_from_sim no)
		(in_bom yes)
		(on_board yes)
		(dnp no)
		(property "Reference" "C102"
			(at 340.36 128.27 90)
			(effects
				(font
					(size 1.27 1.27)
				)
				(justify left)
			)
		)
		(property "Value" "C_4u7_0402"
			(at 330.2 148.59 0)
			(effects
				(font
					(size 1.27 1.27)
					(thickness 0.15)
				)
				(justify left bottom)
				(hide yes)
			)
		)
		(property "Footprint" "antmicro-footprints:C_0402_1005Metric_EIA"
			(at 327.66 148.59 0)
			(effects
				(font
					(size 1.27 1.27)
					(thickness 0.15)
				)
				(justify left bottom)
				(hide yes)
			)
		)
		(property "Datasheet" "https://www.murata.com/products/productdetail?partno=GRM155R61A475MEAA%23"
			(at 325.12 148.59 0)
			(effects
				(font
					(size 1.27 1.27)
					(thickness 0.15)
				)
				(justify left bottom)
				(hide yes)
			)
		)
		(property "Description" ""
			(at 340.36 128.27 0)
			(effects
				(font
					(size 1.27 1.27)
				)
				(hide yes)
			)
		)
		(property "Manufacturer" "Murata"
			(at 320.04 148.59 0)
			(effects
				(font
					(size 1.27 1.27)
					(thickness 0.15)
				)
				(justify left bottom)
				(hide yes)
			)
		)
		(property "MPN" "GRM155R61A475MEAAD"
			(at 322.58 148.59 0)
			(effects
				(font
					(size 1.27 1.27)
					(thickness 0.15)
				)
				(justify left bottom)
				(hide yes)
			)
		)
		(property "Val" "4u7"
			(at 340.995 132.715 90)
			(effects
				(font
					(size 1.27 1.27)
					(thickness 0.15)
				)
				(justify left)
			)
		)
		(property "License" "Apache-2.0"
			(at 317.5 148.59 0)
			(effects
				(font
					(size 1.27 1.27)
					(thickness 0.15)
				)
				(justify left bottom)
				(hide yes)
			)
		)
		(property "Author" "Antmicro"
			(at 314.96 148.59 0)
			(effects
				(font
					(size 1.27 1.27)
					(thickness 0.15)
				)
				(justify left bottom)
				(hide yes)
			)
		)
		(property "Voltage" ""
			(at 312.42 148.59 0)
			(effects
				(font
					(size 1.27 1.27)
				)
				(justify left bottom)
				(hide yes)
			)
		)
		(property "Dielectric" ""
			(at 309.88 148.59 0)
			(effects
				(font
					(size 1.27 1.27)
				)
				(justify left bottom)
				(hide yes)
			)
		)
		(pin "1"
		)
		(pin "2"
		)
		(instances
			(project "data-center-rdimm-ddr5-tester"
				(path ""
					(reference "C102")
					(unit 1)
				)
			)
		)
	)
	(symbol
		(lib_id "antmicropower:GND")
		(at 62.23 198.12 0)
		(unit 1)
		(exclude_from_sim no)
		(in_bom yes)
		(on_board yes)
		(dnp no)
		(fields_autoplaced yes)
		(property "Reference" "#PWR0136"
			(at 62.23 204.47 0)
			(effects
				(font
					(size 1.27 1.27)
				)
				(hide yes)
			)
		)
		(property "Value" "GND"
			(at 60.325 202.565 0)
			(effects
				(font
					(size 1.27 1.27)
					(thickness 0.15)
				)
				(justify left bottom)
			)
		)
		(property "Footprint" ""
			(at 71.12 205.74 0)
			(effects
				(font
					(size 1.27 1.27)
					(thickness 0.15)
				)
				(justify left bottom)
				(hide yes)
			)
		)
		(property "Datasheet" ""
			(at 71.12 210.82 0)
			(effects
				(font
					(size 1.27 1.27)
					(thickness 0.15)
				)
				(justify left bottom)
				(hide yes)
			)
		)
		(property "Description" ""
			(at 62.23 198.12 0)
			(effects
				(font
					(size 1.27 1.27)
				)
				(hide yes)
			)
		)
		(property "Author" "Antmicro"
			(at 71.12 203.2 0)
			(effects
				(font
					(size 1.27 1.27)
					(thickness 0.15)
				)
				(justify left bottom)
				(hide yes)
			)
		)
		(property "License" "Apache-2.0"
			(at 71.12 205.74 0)
			(effects
				(font
					(size 1.27 1.27)
					(thickness 0.15)
				)
				(justify left bottom)
				(hide yes)
			)
		)
		(pin "1"
		)
		(instances
			(project "data-center-rdimm-ddr5-tester"
				(path ""
					(reference "#PWR0136")
					(unit 1)
				)
			)
		)
	)
	(symbol
		(lib_id "antmicroCapacitors0402:C_10u_10V_0402")
		(at 224.79 240.03 90)
		(unit 1)
		(exclude_from_sim no)
		(in_bom yes)
		(on_board yes)
		(dnp no)
		(property "Reference" "C71"
			(at 226.06 235.585 90)
			(effects
				(font
					(size 1.27 1.27)
					(thickness 0.15)
				)
				(justify right)
			)
		)
		(property "Value" "C_10u_10V_0402"
			(at 234.95 219.71 0)
			(effects
				(font
					(size 1.27 1.27)
					(thickness 0.15)
				)
				(justify left bottom)
				(hide yes)
			)
		)
		(property "Footprint" "antmicro-footprints:C_0402_1005Metric_EIA"
			(at 237.49 219.71 0)
			(effects
				(font
					(size 1.27 1.27)
					(thickness 0.15)
				)
				(justify left bottom)
				(hide yes)
			)
		)
		(property "Datasheet" "https://www.murata.com/products/productdetail?partno=GRM155R61A106ME11%23"
			(at 240.03 219.71 0)
			(effects
				(font
					(size 1.27 1.27)
					(thickness 0.15)
				)
				(justify left bottom)
				(hide yes)
			)
		)
		(property "Description" ""
			(at 224.79 240.03 0)
			(effects
				(font
					(size 1.27 1.27)
				)
				(hide yes)
			)
		)
		(property "MPN" "GRM155R61A106ME11D"
			(at 242.57 219.71 0)
			(effects
				(font
					(size 1.27 1.27)
					(thickness 0.15)
				)
				(justify left bottom)
				(hide yes)
			)
		)
		(property "Manufacturer" "Murata"
			(at 245.11 219.71 0)
			(effects
				(font
					(size 1.27 1.27)
					(thickness 0.15)
				)
				(justify left bottom)
				(hide yes)
			)
		)
		(property "License" "Apache-2.0"
			(at 247.65 219.71 0)
			(effects
				(font
					(size 1.27 1.27)
					(thickness 0.15)
				)
				(justify left bottom)
				(hide yes)
			)
		)
		(property "Author" "Antmicro"
			(at 250.19 219.71 0)
			(effects
				(font
					(size 1.27 1.27)
					(thickness 0.15)
				)
				(justify left bottom)
				(hide yes)
			)
		)
		(property "Val" "10u"
			(at 226.06 239.395 90)
			(effects
				(font
					(size 1.27 1.27)
					(thickness 0.15)
				)
				(justify right)
			)
		)
		(property "Voltage" "10V"
			(at 252.73 219.71 0)
			(effects
				(font
					(size 1.27 1.27)
				)
				(justify left bottom)
				(hide yes)
			)
		)
		(property "Dielectric" "X5R"
			(at 255.27 219.71 0)
			(effects
				(font
					(size 1.27 1.27)
				)
				(justify left bottom)
				(hide yes)
			)
		)
		(pin "1"
		)
		(pin "2"
		)
		(instances
			(project "data-center-rdimm-ddr5-tester"
				(path ""
					(reference "C71")
					(unit 1)
				)
			)
		)
	)
	(symbol
		(lib_id "antmicroCapacitors0402:C_100n_0402")
		(at 346.71 100.33 90)
		(unit 1)
		(exclude_from_sim no)
		(in_bom yes)
		(on_board yes)
		(dnp no)
		(property "Reference" "C83"
			(at 347.345 95.885 90)
			(effects
				(font
					(size 1.27 1.27)
					(thickness 0.15)
				)
				(justify right)
			)
		)
		(property "Value" "C_100n_0402"
			(at 356.87 80.01 0)
			(effects
				(font
					(size 1.27 1.27)
					(thickness 0.15)
				)
				(justify left bottom)
				(hide yes)
			)
		)
		(property "Footprint" "antmicro-footprints:C_0402_1005Metric_EIA"
			(at 359.41 80.01 0)
			(effects
				(font
					(size 1.27 1.27)
					(thickness 0.15)
				)
				(justify left bottom)
				(hide yes)
			)
		)
		(property "Datasheet" "https://www.murata.com/products/productdetail?partno=GRM155R61H104KE14%23"
			(at 361.95 80.01 0)
			(effects
				(font
					(size 1.27 1.27)
					(thickness 0.15)
				)
				(justify left bottom)
				(hide yes)
			)
		)
		(property "Description" ""
			(at 346.71 100.33 0)
			(effects
				(font
					(size 1.27 1.27)
				)
				(hide yes)
			)
		)
		(property "MPN" "GRM155R61H104KE14D"
			(at 364.49 80.01 0)
			(effects
				(font
					(size 1.27 1.27)
					(thickness 0.15)
				)
				(justify left bottom)
				(hide yes)
			)
		)
		(property "Manufacturer" "Murata"
			(at 367.03 80.01 0)
			(effects
				(font
					(size 1.27 1.27)
					(thickness 0.15)
				)
				(justify left bottom)
				(hide yes)
			)
		)
		(property "License" "Apache-2.0"
			(at 369.57 80.01 0)
			(effects
				(font
					(size 1.27 1.27)
					(thickness 0.15)
				)
				(justify left bottom)
				(hide yes)
			)
		)
		(property "Author" "Antmicro"
			(at 372.11 80.01 0)
			(effects
				(font
					(size 1.27 1.27)
					(thickness 0.15)
				)
				(justify left bottom)
				(hide yes)
			)
		)
		(property "Val" "100n"
			(at 347.345 99.695 90)
			(effects
				(font
					(size 1.27 1.27)
					(thickness 0.15)
				)
				(justify right)
			)
		)
		(property "Voltage" "50V"
			(at 374.65 80.01 0)
			(effects
				(font
					(size 1.27 1.27)
				)
				(justify left bottom)
				(hide yes)
			)
		)
		(property "Dielectric" "X5R"
			(at 377.19 80.01 0)
			(effects
				(font
					(size 1.27 1.27)
				)
				(justify left bottom)
				(hide yes)
			)
		)
		(pin "1"
		)
		(pin "2"
		)
		(instances
			(project "data-center-rdimm-ddr5-tester"
				(path ""
					(reference "C83")
					(unit 1)
				)
			)
		)
	)
	(symbol
		(lib_id "antmicropower:GND")
		(at 181.61 271.78 0)
		(unit 1)
		(exclude_from_sim no)
		(in_bom yes)
		(on_board yes)
		(dnp no)
		(fields_autoplaced yes)
		(property "Reference" "#PWR060"
			(at 181.61 278.13 0)
			(effects
				(font
					(size 1.27 1.27)
				)
				(hide yes)
			)
		)
		(property "Value" "GND"
			(at 179.705 276.225 0)
			(effects
				(font
					(size 1.27 1.27)
					(thickness 0.15)
				)
				(justify left bottom)
			)
		)
		(property "Footprint" ""
			(at 190.5 279.4 0)
			(effects
				(font
					(size 1.27 1.27)
					(thickness 0.15)
				)
				(justify left bottom)
				(hide yes)
			)
		)
		(property "Datasheet" ""
			(at 190.5 284.48 0)
			(effects
				(font
					(size 1.27 1.27)
					(thickness 0.15)
				)
				(justify left bottom)
				(hide yes)
			)
		)
		(property "Description" ""
			(at 181.61 271.78 0)
			(effects
				(font
					(size 1.27 1.27)
				)
				(hide yes)
			)
		)
		(property "Author" "Antmicro"
			(at 190.5 276.86 0)
			(effects
				(font
					(size 1.27 1.27)
					(thickness 0.15)
				)
				(justify left bottom)
				(hide yes)
			)
		)
		(property "License" "Apache-2.0"
			(at 190.5 279.4 0)
			(effects
				(font
					(size 1.27 1.27)
					(thickness 0.15)
				)
				(justify left bottom)
				(hide yes)
			)
		)
		(pin "1"
		)
		(instances
			(project "data-center-rdimm-ddr5-tester"
				(path ""
					(reference "#PWR060")
					(unit 1)
				)
			)
		)
	)
	(symbol
		(lib_id "antmicropower:GND")
		(at 354.33 66.04 0)
		(unit 1)
		(exclude_from_sim no)
		(in_bom yes)
		(on_board yes)
		(dnp no)
		(fields_autoplaced yes)
		(property "Reference" "#PWR0165"
			(at 354.33 72.39 0)
			(effects
				(font
					(size 1.27 1.27)
				)
				(hide yes)
			)
		)
		(property "Value" "GND"
			(at 352.425 70.485 0)
			(effects
				(font
					(size 1.27 1.27)
					(thickness 0.15)
				)
				(justify left bottom)
			)
		)
		(property "Footprint" ""
			(at 363.22 73.66 0)
			(effects
				(font
					(size 1.27 1.27)
					(thickness 0.15)
				)
				(justify left bottom)
				(hide yes)
			)
		)
		(property "Datasheet" ""
			(at 363.22 78.74 0)
			(effects
				(font
					(size 1.27 1.27)
					(thickness 0.15)
				)
				(justify left bottom)
				(hide yes)
			)
		)
		(property "Description" ""
			(at 354.33 66.04 0)
			(effects
				(font
					(size 1.27 1.27)
				)
				(hide yes)
			)
		)
		(property "Author" "Antmicro"
			(at 363.22 71.12 0)
			(effects
				(font
					(size 1.27 1.27)
					(thickness 0.15)
				)
				(justify left bottom)
				(hide yes)
			)
		)
		(property "License" "Apache-2.0"
			(at 363.22 73.66 0)
			(effects
				(font
					(size 1.27 1.27)
					(thickness 0.15)
				)
				(justify left bottom)
				(hide yes)
			)
		)
		(pin "1"
		)
		(instances
			(project "data-center-rdimm-ddr5-tester"
				(path ""
					(reference "#PWR0165")
					(unit 1)
				)
			)
		)
	)
	(symbol
		(lib_id "antmicropower:GND")
		(at 58.42 242.57 0)
		(unit 1)
		(exclude_from_sim no)
		(in_bom yes)
		(on_board yes)
		(dnp no)
		(fields_autoplaced yes)
		(property "Reference" "#PWR0126"
			(at 58.42 248.92 0)
			(effects
				(font
					(size 1.27 1.27)
				)
				(hide yes)
			)
		)
		(property "Value" "GND"
			(at 56.515 247.015 0)
			(effects
				(font
					(size 1.27 1.27)
					(thickness 0.15)
				)
				(justify left bottom)
			)
		)
		(property "Footprint" ""
			(at 67.31 250.19 0)
			(effects
				(font
					(size 1.27 1.27)
					(thickness 0.15)
				)
				(justify left bottom)
				(hide yes)
			)
		)
		(property "Datasheet" ""
			(at 67.31 255.27 0)
			(effects
				(font
					(size 1.27 1.27)
					(thickness 0.15)
				)
				(justify left bottom)
				(hide yes)
			)
		)
		(property "Description" ""
			(at 58.42 242.57 0)
			(effects
				(font
					(size 1.27 1.27)
				)
				(hide yes)
			)
		)
		(property "Author" "Antmicro"
			(at 67.31 247.65 0)
			(effects
				(font
					(size 1.27 1.27)
					(thickness 0.15)
				)
				(justify left bottom)
				(hide yes)
			)
		)
		(property "License" "Apache-2.0"
			(at 67.31 250.19 0)
			(effects
				(font
					(size 1.27 1.27)
					(thickness 0.15)
				)
				(justify left bottom)
				(hide yes)
			)
		)
		(pin "1"
		)
		(instances
			(project "data-center-rdimm-ddr5-tester"
				(path ""
					(reference "#PWR0126")
					(unit 1)
				)
			)
		)
	)
	(symbol
		(lib_id "antmicroCapacitorsmisc:C_100u_0805")
		(at 88.9 66.04 90)
		(unit 1)
		(exclude_from_sim no)
		(in_bom yes)
		(on_board yes)
		(dnp no)
		(fields_autoplaced yes)
		(property "Reference" "C240"
			(at 91.44 62.2236 90)
			(effects
				(font
					(size 1.27 1.27)
					(thickness 0.15)
				)
				(justify right)
			)
		)
		(property "Value" "C_100u_0805"
			(at 99.06 45.72 0)
			(effects
				(font
					(size 1.27 1.27)
					(thickness 0.15)
				)
				(justify left bottom)
				(hide yes)
			)
		)
		(property "Footprint" "antmicro-footprints:C_0805_2012Metric"
			(at 101.6 45.72 0)
			(effects
				(font
					(size 1.27 1.27)
					(thickness 0.15)
				)
				(justify left bottom)
				(hide yes)
			)
		)
		(property "Datasheet" "https://www.murata.com/products/productdetail?partno=GRM21BR60J107ME15%23"
			(at 104.14 45.72 0)
			(effects
				(font
					(size 1.27 1.27)
					(thickness 0.15)
				)
				(justify left bottom)
				(hide yes)
			)
		)
		(property "Description" ""
			(at 88.9 66.04 0)
			(effects
				(font
					(size 1.27 1.27)
				)
				(hide yes)
			)
		)
		(property "MPN" "GRM21BR60J107ME15L"
			(at 106.68 45.72 0)
			(effects
				(font
					(size 1.27 1.27)
					(thickness 0.15)
				)
				(justify left bottom)
				(hide yes)
			)
		)
		(property "Manufacturer" "Murata"
			(at 109.22 45.72 0)
			(effects
				(font
					(size 1.27 1.27)
					(thickness 0.15)
				)
				(justify left bottom)
				(hide yes)
			)
		)
		(property "License" "Apache-2.0"
			(at 111.76 45.72 0)
			(effects
				(font
					(size 1.27 1.27)
					(thickness 0.15)
				)
				(justify left bottom)
				(hide yes)
			)
		)
		(property "Author" "Antmicro"
			(at 114.3 45.72 0)
			(effects
				(font
					(size 1.27 1.27)
					(thickness 0.15)
				)
				(justify left bottom)
				(hide yes)
			)
		)
		(property "Val" "100u"
			(at 91.44 64.7636 90)
			(effects
				(font
					(size 1.27 1.27)
					(thickness 0.15)
				)
				(justify right)
			)
		)
		(property "Voltage" ""
			(at 116.84 45.72 0)
			(effects
				(font
					(size 1.27 1.27)
				)
				(justify left bottom)
				(hide yes)
			)
		)
		(property "Dielectric" ""
			(at 119.38 45.72 0)
			(effects
				(font
					(size 1.27 1.27)
				)
				(justify left bottom)
				(hide yes)
			)
		)
		(property "Public" "False"
			(at 121.92 45.72 0)
			(effects
				(font
					(size 1.27 1.27)
				)
				(justify left bottom)
				(hide yes)
			)
		)
		(pin "1"
		)
		(pin "2"
		)
		(instances
			(project "data-center-rdimm-ddr5-tester"
				(path ""
					(reference "C240")
					(unit 1)
				)
			)
		)
	)
	(symbol
		(lib_id "antmicropower:GND")
		(at 361.95 101.6 0)
		(unit 1)
		(exclude_from_sim no)
		(in_bom yes)
		(on_board yes)
		(dnp no)
		(fields_autoplaced yes)
		(property "Reference" "#PWR0490"
			(at 361.95 107.95 0)
			(effects
				(font
					(size 1.27 1.27)
				)
				(hide yes)
			)
		)
		(property "Value" "GND"
			(at 360.045 106.045 0)
			(effects
				(font
					(size 1.27 1.27)
					(thickness 0.15)
				)
				(justify left bottom)
			)
		)
		(property "Footprint" ""
			(at 370.84 109.22 0)
			(effects
				(font
					(size 1.27 1.27)
					(thickness 0.15)
				)
				(justify left bottom)
				(hide yes)
			)
		)
		(property "Datasheet" ""
			(at 370.84 114.3 0)
			(effects
				(font
					(size 1.27 1.27)
					(thickness 0.15)
				)
				(justify left bottom)
				(hide yes)
			)
		)
		(property "Description" ""
			(at 361.95 101.6 0)
			(effects
				(font
					(size 1.27 1.27)
				)
				(hide yes)
			)
		)
		(property "Author" "Antmicro"
			(at 370.84 106.68 0)
			(effects
				(font
					(size 1.27 1.27)
					(thickness 0.15)
				)
				(justify left bottom)
				(hide yes)
			)
		)
		(property "License" "Apache-2.0"
			(at 370.84 109.22 0)
			(effects
				(font
					(size 1.27 1.27)
					(thickness 0.15)
				)
				(justify left bottom)
				(hide yes)
			)
		)
		(pin "1"
		)
		(instances
			(project "data-center-rdimm-ddr5-tester"
				(path ""
					(reference "#PWR0490")
					(unit 1)
				)
			)
		)
	)
	(symbol
		(lib_id "antmicroCapacitors0402:C_100n_0402")
		(at 45.72 119.38 90)
		(unit 1)
		(exclude_from_sim no)
		(in_bom yes)
		(on_board yes)
		(dnp no)
		(property "Reference" "C19"
			(at 46.355 114.935 90)
			(effects
				(font
					(size 1.27 1.27)
					(thickness 0.15)
				)
				(justify right)
			)
		)
		(property "Value" "C_100n_0402"
			(at 55.88 99.06 0)
			(effects
				(font
					(size 1.27 1.27)
					(thickness 0.15)
				)
				(justify left bottom)
				(hide yes)
			)
		)
		(property "Footprint" "antmicro-footprints:C_0402_1005Metric_EIA"
			(at 58.42 99.06 0)
			(effects
				(font
					(size 1.27 1.27)
					(thickness 0.15)
				)
				(justify left bottom)
				(hide yes)
			)
		)
		(property "Datasheet" "https://www.murata.com/products/productdetail?partno=GRM155R61H104KE14%23"
			(at 60.96 99.06 0)
			(effects
				(font
					(size 1.27 1.27)
					(thickness 0.15)
				)
				(justify left bottom)
				(hide yes)
			)
		)
		(property "Description" ""
			(at 45.72 119.38 0)
			(effects
				(font
					(size 1.27 1.27)
				)
				(hide yes)
			)
		)
		(property "MPN" "GRM155R61H104KE14D"
			(at 63.5 99.06 0)
			(effects
				(font
					(size 1.27 1.27)
					(thickness 0.15)
				)
				(justify left bottom)
				(hide yes)
			)
		)
		(property "Manufacturer" "Murata"
			(at 66.04 99.06 0)
			(effects
				(font
					(size 1.27 1.27)
					(thickness 0.15)
				)
				(justify left bottom)
				(hide yes)
			)
		)
		(property "License" "Apache-2.0"
			(at 68.58 99.06 0)
			(effects
				(font
					(size 1.27 1.27)
					(thickness 0.15)
				)
				(justify left bottom)
				(hide yes)
			)
		)
		(property "Author" "Antmicro"
			(at 71.12 99.06 0)
			(effects
				(font
					(size 1.27 1.27)
					(thickness 0.15)
				)
				(justify left bottom)
				(hide yes)
			)
		)
		(property "Val" "100n"
			(at 46.355 118.745 90)
			(effects
				(font
					(size 1.27 1.27)
					(thickness 0.15)
				)
				(justify right)
			)
		)
		(property "Voltage" "50V"
			(at 73.66 99.06 0)
			(effects
				(font
					(size 1.27 1.27)
				)
				(justify left bottom)
				(hide yes)
			)
		)
		(property "Dielectric" "X5R"
			(at 76.2 99.06 0)
			(effects
				(font
					(size 1.27 1.27)
				)
				(justify left bottom)
				(hide yes)
			)
		)
		(pin "1"
		)
		(pin "2"
		)
		(instances
			(project "data-center-rdimm-ddr5-tester"
				(path ""
					(reference "C19")
					(unit 1)
				)
			)
		)
	)
	(symbol
		(lib_id "antmicropower:GND")
		(at 354.33 101.6 0)
		(unit 1)
		(exclude_from_sim no)
		(in_bom yes)
		(on_board yes)
		(dnp no)
		(fields_autoplaced yes)
		(property "Reference" "#PWR0487"
			(at 354.33 107.95 0)
			(effects
				(font
					(size 1.27 1.27)
				)
				(hide yes)
			)
		)
		(property "Value" "GND"
			(at 352.425 106.045 0)
			(effects
				(font
					(size 1.27 1.27)
					(thickness 0.15)
				)
				(justify left bottom)
			)
		)
		(property "Footprint" ""
			(at 363.22 109.22 0)
			(effects
				(font
					(size 1.27 1.27)
					(thickness 0.15)
				)
				(justify left bottom)
				(hide yes)
			)
		)
		(property "Datasheet" ""
			(at 363.22 114.3 0)
			(effects
				(font
					(size 1.27 1.27)
					(thickness 0.15)
				)
				(justify left bottom)
				(hide yes)
			)
		)
		(property "Description" ""
			(at 354.33 101.6 0)
			(effects
				(font
					(size 1.27 1.27)
				)
				(hide yes)
			)
		)
		(property "Author" "Antmicro"
			(at 363.22 106.68 0)
			(effects
				(font
					(size 1.27 1.27)
					(thickness 0.15)
				)
				(justify left bottom)
				(hide yes)
			)
		)
		(property "License" "Apache-2.0"
			(at 363.22 109.22 0)
			(effects
				(font
					(size 1.27 1.27)
					(thickness 0.15)
				)
				(justify left bottom)
				(hide yes)
			)
		)
		(pin "1"
		)
		(instances
			(project "data-center-rdimm-ddr5-tester"
				(path ""
					(reference "#PWR0487")
					(unit 1)
				)
			)
		)
	)
	(symbol
		(lib_id "antmicroCapacitors0402:C_1u_25V_0402")
		(at 69.85 172.72 90)
		(unit 1)
		(exclude_from_sim no)
		(in_bom yes)
		(on_board yes)
		(dnp no)
		(fields_autoplaced yes)
		(property "Reference" "C56"
			(at 72.39 168.9036 90)
			(effects
				(font
					(size 1.27 1.27)
					(thickness 0.15)
				)
				(justify right)
			)
		)
		(property "Value" "C_1u_25V_0402"
			(at 80.01 152.4 0)
			(effects
				(font
					(size 1.27 1.27)
					(thickness 0.15)
				)
				(justify left bottom)
				(hide yes)
			)
		)
		(property "Footprint" "antmicro-footprints:C_0402_1005Metric_EIA"
			(at 82.55 152.4 0)
			(effects
				(font
					(size 1.27 1.27)
					(thickness 0.15)
				)
				(justify left bottom)
				(hide yes)
			)
		)
		(property "Datasheet" "https://www.murata.com/products/productdetail?partno=GRM155R61E105KE11%23"
			(at 85.09 152.4 0)
			(effects
				(font
					(size 1.27 1.27)
					(thickness 0.15)
				)
				(justify left bottom)
				(hide yes)
			)
		)
		(property "Description" ""
			(at 69.85 172.72 0)
			(effects
				(font
					(size 1.27 1.27)
				)
				(hide yes)
			)
		)
		(property "MPN" "GRM155R61E105KE11J"
			(at 87.63 152.4 0)
			(effects
				(font
					(size 1.27 1.27)
					(thickness 0.15)
				)
				(justify left bottom)
				(hide yes)
			)
		)
		(property "Manufacturer" "Murata"
			(at 90.17 152.4 0)
			(effects
				(font
					(size 1.27 1.27)
					(thickness 0.15)
				)
				(justify left bottom)
				(hide yes)
			)
		)
		(property "License" "Apache-2.0"
			(at 92.71 152.4 0)
			(effects
				(font
					(size 1.27 1.27)
					(thickness 0.15)
				)
				(justify left bottom)
				(hide yes)
			)
		)
		(property "Author" "Antmicro"
			(at 95.25 152.4 0)
			(effects
				(font
					(size 1.27 1.27)
					(thickness 0.15)
				)
				(justify left bottom)
				(hide yes)
			)
		)
		(property "Val" "1u"
			(at 72.39 171.4436 90)
			(effects
				(font
					(size 1.27 1.27)
					(thickness 0.15)
				)
				(justify right)
			)
		)
		(property "Voltage" "25V"
			(at 97.79 152.4 0)
			(effects
				(font
					(size 1.27 1.27)
				)
				(justify left bottom)
				(hide yes)
			)
		)
		(property "Dielectric" "X5R"
			(at 100.33 152.4 0)
			(effects
				(font
					(size 1.27 1.27)
				)
				(justify left bottom)
				(hide yes)
			)
		)
		(pin "1"
		)
		(pin "2"
		)
		(instances
			(project "data-center-rdimm-ddr5-tester"
				(path ""
					(reference "C56")
					(unit 1)
				)
			)
		)
	)
	(symbol
		(lib_id "antmicroCapacitors0402:C_1u_25V_0402")
		(at 53.34 196.85 90)
		(unit 1)
		(exclude_from_sim no)
		(in_bom yes)
		(on_board yes)
		(dnp no)
		(fields_autoplaced yes)
		(property "Reference" "C84"
			(at 55.88 193.0336 90)
			(effects
				(font
					(size 1.27 1.27)
					(thickness 0.15)
				)
				(justify right)
			)
		)
		(property "Value" "C_1u_25V_0402"
			(at 63.5 176.53 0)
			(effects
				(font
					(size 1.27 1.27)
					(thickness 0.15)
				)
				(justify left bottom)
				(hide yes)
			)
		)
		(property "Footprint" "antmicro-footprints:C_0402_1005Metric_EIA"
			(at 66.04 176.53 0)
			(effects
				(font
					(size 1.27 1.27)
					(thickness 0.15)
				)
				(justify left bottom)
				(hide yes)
			)
		)
		(property "Datasheet" "https://www.murata.com/products/productdetail?partno=GRM155R61E105KE11%23"
			(at 68.58 176.53 0)
			(effects
				(font
					(size 1.27 1.27)
					(thickness 0.15)
				)
				(justify left bottom)
				(hide yes)
			)
		)
		(property "Description" ""
			(at 53.34 196.85 0)
			(effects
				(font
					(size 1.27 1.27)
				)
				(hide yes)
			)
		)
		(property "MPN" "GRM155R61E105KE11J"
			(at 71.12 176.53 0)
			(effects
				(font
					(size 1.27 1.27)
					(thickness 0.15)
				)
				(justify left bottom)
				(hide yes)
			)
		)
		(property "Manufacturer" "Murata"
			(at 73.66 176.53 0)
			(effects
				(font
					(size 1.27 1.27)
					(thickness 0.15)
				)
				(justify left bottom)
				(hide yes)
			)
		)
		(property "License" "Apache-2.0"
			(at 76.2 176.53 0)
			(effects
				(font
					(size 1.27 1.27)
					(thickness 0.15)
				)
				(justify left bottom)
				(hide yes)
			)
		)
		(property "Author" "Antmicro"
			(at 78.74 176.53 0)
			(effects
				(font
					(size 1.27 1.27)
					(thickness 0.15)
				)
				(justify left bottom)
				(hide yes)
			)
		)
		(property "Val" "1u"
			(at 55.88 195.5736 90)
			(effects
				(font
					(size 1.27 1.27)
					(thickness 0.15)
				)
				(justify right)
			)
		)
		(property "Voltage" "25V"
			(at 81.28 176.53 0)
			(effects
				(font
					(size 1.27 1.27)
				)
				(justify left bottom)
				(hide yes)
			)
		)
		(property "Dielectric" "X5R"
			(at 83.82 176.53 0)
			(effects
				(font
					(size 1.27 1.27)
				)
				(justify left bottom)
				(hide yes)
			)
		)
		(pin "1"
		)
		(pin "2"
		)
		(instances
			(project "data-center-rdimm-ddr5-tester"
				(path ""
					(reference "C84")
					(unit 1)
				)
			)
		)
	)
	(symbol
		(lib_id "antmicroCapacitors0402:C_1u_25V_0402")
		(at 53.34 147.32 90)
		(unit 1)
		(exclude_from_sim no)
		(in_bom yes)
		(on_board yes)
		(dnp no)
		(fields_autoplaced yes)
		(property "Reference" "C36"
			(at 55.88 143.5036 90)
			(effects
				(font
					(size 1.27 1.27)
					(thickness 0.15)
				)
				(justify right)
			)
		)
		(property "Value" "C_1u_25V_0402"
			(at 63.5 127 0)
			(effects
				(font
					(size 1.27 1.27)
					(thickness 0.15)
				)
				(justify left bottom)
				(hide yes)
			)
		)
		(property "Footprint" "antmicro-footprints:C_0402_1005Metric_EIA"
			(at 66.04 127 0)
			(effects
				(font
					(size 1.27 1.27)
					(thickness 0.15)
				)
				(justify left bottom)
				(hide yes)
			)
		)
		(property "Datasheet" "https://www.murata.com/products/productdetail?partno=GRM155R61E105KE11%23"
			(at 68.58 127 0)
			(effects
				(font
					(size 1.27 1.27)
					(thickness 0.15)
				)
				(justify left bottom)
				(hide yes)
			)
		)
		(property "Description" ""
			(at 53.34 147.32 0)
			(effects
				(font
					(size 1.27 1.27)
				)
				(hide yes)
			)
		)
		(property "MPN" "GRM155R61E105KE11J"
			(at 71.12 127 0)
			(effects
				(font
					(size 1.27 1.27)
					(thickness 0.15)
				)
				(justify left bottom)
				(hide yes)
			)
		)
		(property "Manufacturer" "Murata"
			(at 73.66 127 0)
			(effects
				(font
					(size 1.27 1.27)
					(thickness 0.15)
				)
				(justify left bottom)
				(hide yes)
			)
		)
		(property "License" "Apache-2.0"
			(at 76.2 127 0)
			(effects
				(font
					(size 1.27 1.27)
					(thickness 0.15)
				)
				(justify left bottom)
				(hide yes)
			)
		)
		(property "Author" "Antmicro"
			(at 78.74 127 0)
			(effects
				(font
					(size 1.27 1.27)
					(thickness 0.15)
				)
				(justify left bottom)
				(hide yes)
			)
		)
		(property "Val" "1u"
			(at 55.88 146.0436 90)
			(effects
				(font
					(size 1.27 1.27)
					(thickness 0.15)
				)
				(justify right)
			)
		)
		(property "Voltage" "25V"
			(at 81.28 127 0)
			(effects
				(font
					(size 1.27 1.27)
				)
				(justify left bottom)
				(hide yes)
			)
		)
		(property "Dielectric" "X5R"
			(at 83.82 127 0)
			(effects
				(font
					(size 1.27 1.27)
				)
				(justify left bottom)
				(hide yes)
			)
		)
		(pin "1"
		)
		(pin "2"
		)
		(instances
			(project "data-center-rdimm-ddr5-tester"
				(path ""
					(reference "C36")
					(unit 1)
				)
			)
		)
	)
	(symbol
		(lib_id "antmicroCapacitors0603:C_47u_0603")
		(at 204.47 266.7 270)
		(unit 1)
		(exclude_from_sim no)
		(in_bom yes)
		(on_board yes)
		(dnp no)
		(property "Reference" "C94"
			(at 204.47 267.335 90)
			(effects
				(font
					(size 1.27 1.27)
				)
				(justify left)
			)
		)
		(property "Value" "C_47u_0603"
			(at 194.31 287.02 0)
			(effects
				(font
					(size 1.27 1.27)
					(thickness 0.15)
				)
				(justify left bottom)
				(hide yes)
			)
		)
		(property "Footprint" "antmicro-footprints:C_0603_1608Metric"
			(at 191.77 287.02 0)
			(effects
				(font
					(size 1.27 1.27)
					(thickness 0.15)
				)
				(justify left bottom)
				(hide yes)
			)
		)
		(property "Datasheet" "https://www.murata.com/products/productdetail?partno=GRM188R60J476ME15%23"
			(at 189.23 287.02 0)
			(effects
				(font
					(size 1.27 1.27)
					(thickness 0.15)
				)
				(justify left bottom)
				(hide yes)
			)
		)
		(property "Description" ""
			(at 204.47 266.7 0)
			(effects
				(font
					(size 1.27 1.27)
				)
				(hide yes)
			)
		)
		(property "Manufacturer" "Murata"
			(at 184.15 287.02 0)
			(effects
				(font
					(size 1.27 1.27)
					(thickness 0.15)
				)
				(justify left bottom)
				(hide yes)
			)
		)
		(property "MPN" "GRM188R60J476ME15D"
			(at 186.69 287.02 0)
			(effects
				(font
					(size 1.27 1.27)
					(thickness 0.15)
				)
				(justify left bottom)
				(hide yes)
			)
		)
		(property "Val" "47u"
			(at 204.47 271.145 90)
			(effects
				(font
					(size 1.27 1.27)
					(thickness 0.15)
				)
				(justify left)
			)
		)
		(property "License" "Apache-2.0"
			(at 181.61 287.02 0)
			(effects
				(font
					(size 1.27 1.27)
					(thickness 0.15)
				)
				(justify left bottom)
				(hide yes)
			)
		)
		(property "Author" "Antmicro"
			(at 179.07 287.02 0)
			(effects
				(font
					(size 1.27 1.27)
					(thickness 0.15)
				)
				(justify left bottom)
				(hide yes)
			)
		)
		(property "Voltage" ""
			(at 176.53 287.02 0)
			(effects
				(font
					(size 1.27 1.27)
				)
				(justify left bottom)
				(hide yes)
			)
		)
		(property "Dielectric" ""
			(at 173.99 287.02 0)
			(effects
				(font
					(size 1.27 1.27)
				)
				(justify left bottom)
				(hide yes)
			)
		)
		(pin "1"
		)
		(pin "2"
		)
		(instances
			(project "data-center-rdimm-ddr5-tester"
				(path ""
					(reference "C94")
					(unit 1)
				)
			)
		)
	)
	(symbol
		(lib_id "antmicroCapacitors0402:C_1u_25V_0402")
		(at 102.87 172.72 90)
		(unit 1)
		(exclude_from_sim no)
		(in_bom yes)
		(on_board yes)
		(dnp no)
		(fields_autoplaced yes)
		(property "Reference" "C75"
			(at 105.41 168.9036 90)
			(effects
				(font
					(size 1.27 1.27)
					(thickness 0.15)
				)
				(justify right)
			)
		)
		(property "Value" "C_1u_25V_0402"
			(at 113.03 152.4 0)
			(effects
				(font
					(size 1.27 1.27)
					(thickness 0.15)
				)
				(justify left bottom)
				(hide yes)
			)
		)
		(property "Footprint" "antmicro-footprints:C_0402_1005Metric_EIA"
			(at 115.57 152.4 0)
			(effects
				(font
					(size 1.27 1.27)
					(thickness 0.15)
				)
				(justify left bottom)
				(hide yes)
			)
		)
		(property "Datasheet" "https://www.murata.com/products/productdetail?partno=GRM155R61E105KE11%23"
			(at 118.11 152.4 0)
			(effects
				(font
					(size 1.27 1.27)
					(thickness 0.15)
				)
				(justify left bottom)
				(hide yes)
			)
		)
		(property "Description" ""
			(at 102.87 172.72 0)
			(effects
				(font
					(size 1.27 1.27)
				)
				(hide yes)
			)
		)
		(property "MPN" "GRM155R61E105KE11J"
			(at 120.65 152.4 0)
			(effects
				(font
					(size 1.27 1.27)
					(thickness 0.15)
				)
				(justify left bottom)
				(hide yes)
			)
		)
		(property "Manufacturer" "Murata"
			(at 123.19 152.4 0)
			(effects
				(font
					(size 1.27 1.27)
					(thickness 0.15)
				)
				(justify left bottom)
				(hide yes)
			)
		)
		(property "License" "Apache-2.0"
			(at 125.73 152.4 0)
			(effects
				(font
					(size 1.27 1.27)
					(thickness 0.15)
				)
				(justify left bottom)
				(hide yes)
			)
		)
		(property "Author" "Antmicro"
			(at 128.27 152.4 0)
			(effects
				(font
					(size 1.27 1.27)
					(thickness 0.15)
				)
				(justify left bottom)
				(hide yes)
			)
		)
		(property "Val" "1u"
			(at 105.41 171.4436 90)
			(effects
				(font
					(size 1.27 1.27)
					(thickness 0.15)
				)
				(justify right)
			)
		)
		(property "Voltage" "25V"
			(at 130.81 152.4 0)
			(effects
				(font
					(size 1.27 1.27)
				)
				(justify left bottom)
				(hide yes)
			)
		)
		(property "Dielectric" "X5R"
			(at 133.35 152.4 0)
			(effects
				(font
					(size 1.27 1.27)
				)
				(justify left bottom)
				(hide yes)
			)
		)
		(pin "1"
		)
		(pin "2"
		)
		(instances
			(project "data-center-rdimm-ddr5-tester"
				(path ""
					(reference "C75")
					(unit 1)
				)
			)
		)
	)
	(symbol
		(lib_id "antmicroCapacitors0402:C_100n_0402")
		(at 369.57 100.33 90)
		(unit 1)
		(exclude_from_sim no)
		(in_bom yes)
		(on_board yes)
		(dnp no)
		(property "Reference" "C312"
			(at 370.205 95.885 90)
			(effects
				(font
					(size 1.27 1.27)
					(thickness 0.15)
				)
				(justify right)
			)
		)
		(property "Value" "C_100n_0402"
			(at 379.73 80.01 0)
			(effects
				(font
					(size 1.27 1.27)
					(thickness 0.15)
				)
				(justify left bottom)
				(hide yes)
			)
		)
		(property "Footprint" "antmicro-footprints:C_0402_1005Metric_EIA"
			(at 382.27 80.01 0)
			(effects
				(font
					(size 1.27 1.27)
					(thickness 0.15)
				)
				(justify left bottom)
				(hide yes)
			)
		)
		(property "Datasheet" "https://www.murata.com/products/productdetail?partno=GRM155R61H104KE14%23"
			(at 384.81 80.01 0)
			(effects
				(font
					(size 1.27 1.27)
					(thickness 0.15)
				)
				(justify left bottom)
				(hide yes)
			)
		)
		(property "Description" ""
			(at 369.57 100.33 0)
			(effects
				(font
					(size 1.27 1.27)
				)
				(hide yes)
			)
		)
		(property "MPN" "GRM155R61H104KE14D"
			(at 387.35 80.01 0)
			(effects
				(font
					(size 1.27 1.27)
					(thickness 0.15)
				)
				(justify left bottom)
				(hide yes)
			)
		)
		(property "Manufacturer" "Murata"
			(at 389.89 80.01 0)
			(effects
				(font
					(size 1.27 1.27)
					(thickness 0.15)
				)
				(justify left bottom)
				(hide yes)
			)
		)
		(property "License" "Apache-2.0"
			(at 392.43 80.01 0)
			(effects
				(font
					(size 1.27 1.27)
					(thickness 0.15)
				)
				(justify left bottom)
				(hide yes)
			)
		)
		(property "Author" "Antmicro"
			(at 394.97 80.01 0)
			(effects
				(font
					(size 1.27 1.27)
					(thickness 0.15)
				)
				(justify left bottom)
				(hide yes)
			)
		)
		(property "Val" "100n"
			(at 370.205 99.695 90)
			(effects
				(font
					(size 1.27 1.27)
					(thickness 0.15)
				)
				(justify right)
			)
		)
		(property "Voltage" "50V"
			(at 397.51 80.01 0)
			(effects
				(font
					(size 1.27 1.27)
				)
				(justify left bottom)
				(hide yes)
			)
		)
		(property "Dielectric" "X5R"
			(at 400.05 80.01 0)
			(effects
				(font
					(size 1.27 1.27)
				)
				(justify left bottom)
				(hide yes)
			)
		)
		(pin "1"
		)
		(pin "2"
		)
		(instances
			(project "data-center-rdimm-ddr5-tester"
				(path ""
					(reference "C312")
					(unit 1)
				)
			)
		)
	)
	(symbol
		(lib_id "antmicropower:GND")
		(at 246.38 273.05 0)
		(unit 1)
		(exclude_from_sim no)
		(in_bom yes)
		(on_board yes)
		(dnp no)
		(fields_autoplaced yes)
		(property "Reference" "#PWR062"
			(at 246.38 279.4 0)
			(effects
				(font
					(size 1.27 1.27)
				)
				(hide yes)
			)
		)
		(property "Value" "GND"
			(at 244.475 277.495 0)
			(effects
				(font
					(size 1.27 1.27)
					(thickness 0.15)
				)
				(justify left bottom)
			)
		)
		(property "Footprint" ""
			(at 255.27 280.67 0)
			(effects
				(font
					(size 1.27 1.27)
					(thickness 0.15)
				)
				(justify left bottom)
				(hide yes)
			)
		)
		(property "Datasheet" ""
			(at 255.27 285.75 0)
			(effects
				(font
					(size 1.27 1.27)
					(thickness 0.15)
				)
				(justify left bottom)
				(hide yes)
			)
		)
		(property "Description" ""
			(at 246.38 273.05 0)
			(effects
				(font
					(size 1.27 1.27)
				)
				(hide yes)
			)
		)
		(property "Author" "Antmicro"
			(at 255.27 278.13 0)
			(effects
				(font
					(size 1.27 1.27)
					(thickness 0.15)
				)
				(justify left bottom)
				(hide yes)
			)
		)
		(property "License" "Apache-2.0"
			(at 255.27 280.67 0)
			(effects
				(font
					(size 1.27 1.27)
					(thickness 0.15)
				)
				(justify left bottom)
				(hide yes)
			)
		)
		(pin "1"
		)
		(instances
			(project "data-center-rdimm-ddr5-tester"
				(path ""
					(reference "#PWR062")
					(unit 1)
				)
			)
		)
	)
	(symbol
		(lib_id "antmicropower:+1V8")
		(at 256.54 229.87 0)
		(unit 1)
		(exclude_from_sim no)
		(in_bom yes)
		(on_board yes)
		(dnp no)
		(fields_autoplaced yes)
		(property "Reference" "#PWR0135"
			(at 271.78 232.41 0)
			(effects
				(font
					(size 1.27 1.27)
					(thickness 0.15)
				)
				(justify left bottom)
				(hide yes)
			)
		)
		(property "Value" "+1V8"
			(at 256.54 225.425 0)
			(effects
				(font
					(size 1.27 1.27)
					(thickness 0.15)
				)
			)
		)
		(property "Footprint" ""
			(at 271.78 237.49 0)
			(effects
				(font
					(size 1.27 1.27)
					(thickness 0.15)
				)
				(justify left bottom)
				(hide yes)
			)
		)
		(property "Datasheet" ""
			(at 271.78 240.03 0)
			(effects
				(font
					(size 1.27 1.27)
					(thickness 0.15)
				)
				(justify left bottom)
				(hide yes)
			)
		)
		(property "Description" ""
			(at 256.54 229.87 0)
			(effects
				(font
					(size 1.27 1.27)
				)
				(hide yes)
			)
		)
		(property "Author" "Antmicro"
			(at 271.78 234.95 0)
			(effects
				(font
					(size 1.27 1.27)
					(thickness 0.15)
				)
				(justify left bottom)
				(hide yes)
			)
		)
		(property "License" "Apache-2.0"
			(at 271.78 237.49 0)
			(effects
				(font
					(size 1.27 1.27)
					(thickness 0.15)
				)
				(justify left bottom)
				(hide yes)
			)
		)
		(pin "1"
		)
		(instances
			(project "data-center-rdimm-ddr5-tester"
				(path ""
					(reference "#PWR0135")
					(unit 1)
				)
			)
		)
	)
	(symbol
		(lib_id "antmicropower:GND")
		(at 349.25 134.62 0)
		(unit 1)
		(exclude_from_sim no)
		(in_bom yes)
		(on_board yes)
		(dnp no)
		(fields_autoplaced yes)
		(property "Reference" "#PWR0152"
			(at 349.25 140.97 0)
			(effects
				(font
					(size 1.27 1.27)
				)
				(hide yes)
			)
		)
		(property "Value" "GND"
			(at 347.345 139.065 0)
			(effects
				(font
					(size 1.27 1.27)
					(thickness 0.15)
				)
				(justify left bottom)
			)
		)
		(property "Footprint" ""
			(at 358.14 142.24 0)
			(effects
				(font
					(size 1.27 1.27)
					(thickness 0.15)
				)
				(justify left bottom)
				(hide yes)
			)
		)
		(property "Datasheet" ""
			(at 358.14 147.32 0)
			(effects
				(font
					(size 1.27 1.27)
					(thickness 0.15)
				)
				(justify left bottom)
				(hide yes)
			)
		)
		(property "Description" ""
			(at 349.25 134.62 0)
			(effects
				(font
					(size 1.27 1.27)
				)
				(hide yes)
			)
		)
		(property "Author" "Antmicro"
			(at 358.14 139.7 0)
			(effects
				(font
					(size 1.27 1.27)
					(thickness 0.15)
				)
				(justify left bottom)
				(hide yes)
			)
		)
		(property "License" "Apache-2.0"
			(at 358.14 142.24 0)
			(effects
				(font
					(size 1.27 1.27)
					(thickness 0.15)
				)
				(justify left bottom)
				(hide yes)
			)
		)
		(pin "1"
		)
		(instances
			(project "data-center-rdimm-ddr5-tester"
				(path ""
					(reference "#PWR0152")
					(unit 1)
				)
			)
		)
	)
	(symbol
		(lib_id "antmicropower:GND")
		(at 36.83 173.99 0)
		(unit 1)
		(exclude_from_sim no)
		(in_bom yes)
		(on_board yes)
		(dnp no)
		(fields_autoplaced yes)
		(property "Reference" "#PWR097"
			(at 36.83 180.34 0)
			(effects
				(font
					(size 1.27 1.27)
				)
				(hide yes)
			)
		)
		(property "Value" "GND"
			(at 34.925 178.435 0)
			(effects
				(font
					(size 1.27 1.27)
					(thickness 0.15)
				)
				(justify left bottom)
			)
		)
		(property "Footprint" ""
			(at 45.72 181.61 0)
			(effects
				(font
					(size 1.27 1.27)
					(thickness 0.15)
				)
				(justify left bottom)
				(hide yes)
			)
		)
		(property "Datasheet" ""
			(at 45.72 186.69 0)
			(effects
				(font
					(size 1.27 1.27)
					(thickness 0.15)
				)
				(justify left bottom)
				(hide yes)
			)
		)
		(property "Description" ""
			(at 36.83 173.99 0)
			(effects
				(font
					(size 1.27 1.27)
				)
				(hide yes)
			)
		)
		(property "Author" "Antmicro"
			(at 45.72 179.07 0)
			(effects
				(font
					(size 1.27 1.27)
					(thickness 0.15)
				)
				(justify left bottom)
				(hide yes)
			)
		)
		(property "License" "Apache-2.0"
			(at 45.72 181.61 0)
			(effects
				(font
					(size 1.27 1.27)
					(thickness 0.15)
				)
				(justify left bottom)
				(hide yes)
			)
		)
		(pin "1"
		)
		(instances
			(project "data-center-rdimm-ddr5-tester"
				(path ""
					(reference "#PWR097")
					(unit 1)
				)
			)
		)
	)
	(symbol
		(lib_id "antmicropower:+0V9_MGTAVCC")
		(at 242.57 100.33 0)
		(unit 1)
		(exclude_from_sim no)
		(in_bom yes)
		(on_board yes)
		(dnp no)
		(property "Reference" "#PWR027"
			(at 242.57 104.14 0)
			(effects
				(font
					(size 1.27 1.27)
				)
				(hide yes)
			)
		)
		(property "Value" "+0V9_MGTAVCC"
			(at 242.57 95.885 0)
			(effects
				(font
					(size 1.27 1.27)
				)
			)
		)
		(property "Footprint" ""
			(at 242.57 100.33 0)
			(effects
				(font
					(size 1.27 1.27)
				)
				(hide yes)
			)
		)
		(property "Datasheet" ""
			(at 242.57 100.33 0)
			(effects
				(font
					(size 1.27 1.27)
				)
				(hide yes)
			)
		)
		(property "Description" ""
			(at 242.57 100.33 0)
			(effects
				(font
					(size 1.27 1.27)
				)
				(hide yes)
			)
		)
		(pin "1"
		)
		(instances
			(project "data-center-rdimm-ddr5-tester"
				(path ""
					(reference "#PWR027")
					(unit 1)
				)
			)
		)
	)
	(symbol
		(lib_id "antmicroCapacitors0603:C_47u_0603")
		(at 325.12 128.27 270)
		(unit 1)
		(exclude_from_sim no)
		(in_bom yes)
		(on_board yes)
		(dnp no)
		(property "Reference" "C63"
			(at 325.12 128.905 90)
			(effects
				(font
					(size 1.27 1.27)
				)
				(justify left)
			)
		)
		(property "Value" "C_47u_0603"
			(at 314.96 148.59 0)
			(effects
				(font
					(size 1.27 1.27)
					(thickness 0.15)
				)
				(justify left bottom)
				(hide yes)
			)
		)
		(property "Footprint" "antmicro-footprints:C_0603_1608Metric"
			(at 312.42 148.59 0)
			(effects
				(font
					(size 1.27 1.27)
					(thickness 0.15)
				)
				(justify left bottom)
				(hide yes)
			)
		)
		(property "Datasheet" "https://www.murata.com/products/productdetail?partno=GRM188R60J476ME15%23"
			(at 309.88 148.59 0)
			(effects
				(font
					(size 1.27 1.27)
					(thickness 0.15)
				)
				(justify left bottom)
				(hide yes)
			)
		)
		(property "Description" ""
			(at 325.12 128.27 0)
			(effects
				(font
					(size 1.27 1.27)
				)
				(hide yes)
			)
		)
		(property "Manufacturer" "Murata"
			(at 304.8 148.59 0)
			(effects
				(font
					(size 1.27 1.27)
					(thickness 0.15)
				)
				(justify left bottom)
				(hide yes)
			)
		)
		(property "MPN" "GRM188R60J476ME15D"
			(at 307.34 148.59 0)
			(effects
				(font
					(size 1.27 1.27)
					(thickness 0.15)
				)
				(justify left bottom)
				(hide yes)
			)
		)
		(property "Val" "47u"
			(at 325.12 132.715 90)
			(effects
				(font
					(size 1.27 1.27)
					(thickness 0.15)
				)
				(justify left)
			)
		)
		(property "License" "Apache-2.0"
			(at 302.26 148.59 0)
			(effects
				(font
					(size 1.27 1.27)
					(thickness 0.15)
				)
				(justify left bottom)
				(hide yes)
			)
		)
		(property "Author" "Antmicro"
			(at 299.72 148.59 0)
			(effects
				(font
					(size 1.27 1.27)
					(thickness 0.15)
				)
				(justify left bottom)
				(hide yes)
			)
		)
		(property "Voltage" ""
			(at 297.18 148.59 0)
			(effects
				(font
					(size 1.27 1.27)
				)
				(justify left bottom)
				(hide yes)
			)
		)
		(property "Dielectric" ""
			(at 294.64 148.59 0)
			(effects
				(font
					(size 1.27 1.27)
				)
				(justify left bottom)
				(hide yes)
			)
		)
		(pin "1"
		)
		(pin "2"
		)
		(instances
			(project "data-center-rdimm-ddr5-tester"
				(path ""
					(reference "C63")
					(unit 1)
				)
			)
		)
	)
	(symbol
		(lib_id "antmicroCapacitors0402:C_100n_0402")
		(at 354.33 64.77 90)
		(unit 1)
		(exclude_from_sim no)
		(in_bom yes)
		(on_board yes)
		(dnp no)
		(property "Reference" "C105"
			(at 354.965 60.325 90)
			(effects
				(font
					(size 1.27 1.27)
					(thickness 0.15)
				)
				(justify right)
			)
		)
		(property "Value" "C_100n_0402"
			(at 364.49 44.45 0)
			(effects
				(font
					(size 1.27 1.27)
					(thickness 0.15)
				)
				(justify left bottom)
				(hide yes)
			)
		)
		(property "Footprint" "antmicro-footprints:C_0402_1005Metric_EIA"
			(at 367.03 44.45 0)
			(effects
				(font
					(size 1.27 1.27)
					(thickness 0.15)
				)
				(justify left bottom)
				(hide yes)
			)
		)
		(property "Datasheet" "https://www.murata.com/products/productdetail?partno=GRM155R61H104KE14%23"
			(at 369.57 44.45 0)
			(effects
				(font
					(size 1.27 1.27)
					(thickness 0.15)
				)
				(justify left bottom)
				(hide yes)
			)
		)
		(property "Description" ""
			(at 354.33 64.77 0)
			(effects
				(font
					(size 1.27 1.27)
				)
				(hide yes)
			)
		)
		(property "MPN" "GRM155R61H104KE14D"
			(at 372.11 44.45 0)
			(effects
				(font
					(size 1.27 1.27)
					(thickness 0.15)
				)
				(justify left bottom)
				(hide yes)
			)
		)
		(property "Manufacturer" "Murata"
			(at 374.65 44.45 0)
			(effects
				(font
					(size 1.27 1.27)
					(thickness 0.15)
				)
				(justify left bottom)
				(hide yes)
			)
		)
		(property "License" "Apache-2.0"
			(at 377.19 44.45 0)
			(effects
				(font
					(size 1.27 1.27)
					(thickness 0.15)
				)
				(justify left bottom)
				(hide yes)
			)
		)
		(property "Author" "Antmicro"
			(at 379.73 44.45 0)
			(effects
				(font
					(size 1.27 1.27)
					(thickness 0.15)
				)
				(justify left bottom)
				(hide yes)
			)
		)
		(property "Val" "100n"
			(at 354.965 64.135 90)
			(effects
				(font
					(size 1.27 1.27)
					(thickness 0.15)
				)
				(justify right)
			)
		)
		(property "Voltage" "50V"
			(at 382.27 44.45 0)
			(effects
				(font
					(size 1.27 1.27)
				)
				(justify left bottom)
				(hide yes)
			)
		)
		(property "Dielectric" "X5R"
			(at 384.81 44.45 0)
			(effects
				(font
					(size 1.27 1.27)
				)
				(justify left bottom)
				(hide yes)
			)
		)
		(pin "1"
		)
		(pin "2"
		)
		(instances
			(project "data-center-rdimm-ddr5-tester"
				(path ""
					(reference "C105")
					(unit 1)
				)
			)
		)
	)
	(symbol
		(lib_id "antmicroCapacitors0402:C_100n_0402")
		(at 95.25 119.38 90)
		(unit 1)
		(exclude_from_sim no)
		(in_bom yes)
		(on_board yes)
		(dnp no)
		(property "Reference" "C61"
			(at 95.885 114.935 90)
			(effects
				(font
					(size 1.27 1.27)
					(thickness 0.15)
				)
				(justify right)
			)
		)
		(property "Value" "C_100n_0402"
			(at 105.41 99.06 0)
			(effects
				(font
					(size 1.27 1.27)
					(thickness 0.15)
				)
				(justify left bottom)
				(hide yes)
			)
		)
		(property "Footprint" "antmicro-footprints:C_0402_1005Metric_EIA"
			(at 107.95 99.06 0)
			(effects
				(font
					(size 1.27 1.27)
					(thickness 0.15)
				)
				(justify left bottom)
				(hide yes)
			)
		)
		(property "Datasheet" "https://www.murata.com/products/productdetail?partno=GRM155R61H104KE14%23"
			(at 110.49 99.06 0)
			(effects
				(font
					(size 1.27 1.27)
					(thickness 0.15)
				)
				(justify left bottom)
				(hide yes)
			)
		)
		(property "Description" ""
			(at 95.25 119.38 0)
			(effects
				(font
					(size 1.27 1.27)
				)
				(hide yes)
			)
		)
		(property "MPN" "GRM155R61H104KE14D"
			(at 113.03 99.06 0)
			(effects
				(font
					(size 1.27 1.27)
					(thickness 0.15)
				)
				(justify left bottom)
				(hide yes)
			)
		)
		(property "Manufacturer" "Murata"
			(at 115.57 99.06 0)
			(effects
				(font
					(size 1.27 1.27)
					(thickness 0.15)
				)
				(justify left bottom)
				(hide yes)
			)
		)
		(property "License" "Apache-2.0"
			(at 118.11 99.06 0)
			(effects
				(font
					(size 1.27 1.27)
					(thickness 0.15)
				)
				(justify left bottom)
				(hide yes)
			)
		)
		(property "Author" "Antmicro"
			(at 120.65 99.06 0)
			(effects
				(font
					(size 1.27 1.27)
					(thickness 0.15)
				)
				(justify left bottom)
				(hide yes)
			)
		)
		(property "Val" "100n"
			(at 95.885 118.745 90)
			(effects
				(font
					(size 1.27 1.27)
					(thickness 0.15)
				)
				(justify right)
			)
		)
		(property "Voltage" "50V"
			(at 123.19 99.06 0)
			(effects
				(font
					(size 1.27 1.27)
				)
				(justify left bottom)
				(hide yes)
			)
		)
		(property "Dielectric" "X5R"
			(at 125.73 99.06 0)
			(effects
				(font
					(size 1.27 1.27)
				)
				(justify left bottom)
				(hide yes)
			)
		)
		(pin "1"
		)
		(pin "2"
		)
		(instances
			(project "data-center-rdimm-ddr5-tester"
				(path ""
					(reference "C61")
					(unit 1)
				)
			)
		)
	)
	(symbol
		(lib_id "antmicroCapacitors0402:C_1u_25V_0402")
		(at 95.25 196.85 90)
		(unit 1)
		(exclude_from_sim no)
		(in_bom yes)
		(on_board yes)
		(dnp no)
		(fields_autoplaced yes)
		(property "Reference" "C246"
			(at 97.79 193.0336 90)
			(effects
				(font
					(size 1.27 1.27)
					(thickness 0.15)
				)
				(justify right)
			)
		)
		(property "Value" "C_1u_25V_0402"
			(at 105.41 176.53 0)
			(effects
				(font
					(size 1.27 1.27)
					(thickness 0.15)
				)
				(justify left bottom)
				(hide yes)
			)
		)
		(property "Footprint" "antmicro-footprints:C_0402_1005Metric_EIA"
			(at 107.95 176.53 0)
			(effects
				(font
					(size 1.27 1.27)
					(thickness 0.15)
				)
				(justify left bottom)
				(hide yes)
			)
		)
		(property "Datasheet" "https://www.murata.com/products/productdetail?partno=GRM155R61E105KE11%23"
			(at 110.49 176.53 0)
			(effects
				(font
					(size 1.27 1.27)
					(thickness 0.15)
				)
				(justify left bottom)
				(hide yes)
			)
		)
		(property "Description" ""
			(at 95.25 196.85 0)
			(effects
				(font
					(size 1.27 1.27)
				)
				(hide yes)
			)
		)
		(property "MPN" "GRM155R61E105KE11J"
			(at 113.03 176.53 0)
			(effects
				(font
					(size 1.27 1.27)
					(thickness 0.15)
				)
				(justify left bottom)
				(hide yes)
			)
		)
		(property "Manufacturer" "Murata"
			(at 115.57 176.53 0)
			(effects
				(font
					(size 1.27 1.27)
					(thickness 0.15)
				)
				(justify left bottom)
				(hide yes)
			)
		)
		(property "License" "Apache-2.0"
			(at 118.11 176.53 0)
			(effects
				(font
					(size 1.27 1.27)
					(thickness 0.15)
				)
				(justify left bottom)
				(hide yes)
			)
		)
		(property "Author" "Antmicro"
			(at 120.65 176.53 0)
			(effects
				(font
					(size 1.27 1.27)
					(thickness 0.15)
				)
				(justify left bottom)
				(hide yes)
			)
		)
		(property "Val" "1u"
			(at 97.79 195.5736 90)
			(effects
				(font
					(size 1.27 1.27)
					(thickness 0.15)
				)
				(justify right)
			)
		)
		(property "Voltage" "25V"
			(at 123.19 176.53 0)
			(effects
				(font
					(size 1.27 1.27)
				)
				(justify left bottom)
				(hide yes)
			)
		)
		(property "Dielectric" "X5R"
			(at 125.73 176.53 0)
			(effects
				(font
					(size 1.27 1.27)
				)
				(justify left bottom)
				(hide yes)
			)
		)
		(pin "1"
		)
		(pin "2"
		)
		(instances
			(project "data-center-rdimm-ddr5-tester"
				(path ""
					(reference "C246")
					(unit 1)
				)
			)
		)
	)
	(symbol
		(lib_id "antmicropower:GND")
		(at 325.12 134.62 0)
		(unit 1)
		(exclude_from_sim no)
		(in_bom yes)
		(on_board yes)
		(dnp no)
		(fields_autoplaced yes)
		(property "Reference" "#PWR0114"
			(at 325.12 140.97 0)
			(effects
				(font
					(size 1.27 1.27)
				)
				(hide yes)
			)
		)
		(property "Value" "GND"
			(at 323.215 139.065 0)
			(effects
				(font
					(size 1.27 1.27)
					(thickness 0.15)
				)
				(justify left bottom)
			)
		)
		(property "Footprint" ""
			(at 334.01 142.24 0)
			(effects
				(font
					(size 1.27 1.27)
					(thickness 0.15)
				)
				(justify left bottom)
				(hide yes)
			)
		)
		(property "Datasheet" ""
			(at 334.01 147.32 0)
			(effects
				(font
					(size 1.27 1.27)
					(thickness 0.15)
				)
				(justify left bottom)
				(hide yes)
			)
		)
		(property "Description" ""
			(at 325.12 134.62 0)
			(effects
				(font
					(size 1.27 1.27)
				)
				(hide yes)
			)
		)
		(property "Author" "Antmicro"
			(at 334.01 139.7 0)
			(effects
				(font
					(size 1.27 1.27)
					(thickness 0.15)
				)
				(justify left bottom)
				(hide yes)
			)
		)
		(property "License" "Apache-2.0"
			(at 334.01 142.24 0)
			(effects
				(font
					(size 1.27 1.27)
					(thickness 0.15)
				)
				(justify left bottom)
				(hide yes)
			)
		)
		(pin "1"
		)
		(instances
			(project "data-center-rdimm-ddr5-tester"
				(path ""
					(reference "#PWR0114")
					(unit 1)
				)
			)
		)
	)
	(symbol
		(lib_id "antmicroCapacitors0402:C_100n_0402")
		(at 361.95 64.77 90)
		(unit 1)
		(exclude_from_sim no)
		(in_bom yes)
		(on_board yes)
		(dnp no)
		(property "Reference" "C106"
			(at 362.585 60.325 90)
			(effects
				(font
					(size 1.27 1.27)
					(thickness 0.15)
				)
				(justify right)
			)
		)
		(property "Value" "C_100n_0402"
			(at 372.11 44.45 0)
			(effects
				(font
					(size 1.27 1.27)
					(thickness 0.15)
				)
				(justify left bottom)
				(hide yes)
			)
		)
		(property "Footprint" "antmicro-footprints:C_0402_1005Metric_EIA"
			(at 374.65 44.45 0)
			(effects
				(font
					(size 1.27 1.27)
					(thickness 0.15)
				)
				(justify left bottom)
				(hide yes)
			)
		)
		(property "Datasheet" "https://www.murata.com/products/productdetail?partno=GRM155R61H104KE14%23"
			(at 377.19 44.45 0)
			(effects
				(font
					(size 1.27 1.27)
					(thickness 0.15)
				)
				(justify left bottom)
				(hide yes)
			)
		)
		(property "Description" ""
			(at 361.95 64.77 0)
			(effects
				(font
					(size 1.27 1.27)
				)
				(hide yes)
			)
		)
		(property "MPN" "GRM155R61H104KE14D"
			(at 379.73 44.45 0)
			(effects
				(font
					(size 1.27 1.27)
					(thickness 0.15)
				)
				(justify left bottom)
				(hide yes)
			)
		)
		(property "Manufacturer" "Murata"
			(at 382.27 44.45 0)
			(effects
				(font
					(size 1.27 1.27)
					(thickness 0.15)
				)
				(justify left bottom)
				(hide yes)
			)
		)
		(property "License" "Apache-2.0"
			(at 384.81 44.45 0)
			(effects
				(font
					(size 1.27 1.27)
					(thickness 0.15)
				)
				(justify left bottom)
				(hide yes)
			)
		)
		(property "Author" "Antmicro"
			(at 387.35 44.45 0)
			(effects
				(font
					(size 1.27 1.27)
					(thickness 0.15)
				)
				(justify left bottom)
				(hide yes)
			)
		)
		(property "Val" "100n"
			(at 362.585 64.135 90)
			(effects
				(font
					(size 1.27 1.27)
					(thickness 0.15)
				)
				(justify right)
			)
		)
		(property "Voltage" "50V"
			(at 389.89 44.45 0)
			(effects
				(font
					(size 1.27 1.27)
				)
				(justify left bottom)
				(hide yes)
			)
		)
		(property "Dielectric" "X5R"
			(at 392.43 44.45 0)
			(effects
				(font
					(size 1.27 1.27)
				)
				(justify left bottom)
				(hide yes)
			)
		)
		(pin "1"
		)
		(pin "2"
		)
		(instances
			(project "data-center-rdimm-ddr5-tester"
				(path ""
					(reference "C106")
					(unit 1)
				)
			)
		)
	)
	(symbol
		(lib_id "antmicropower:+1V8")
		(at 29.21 231.14 0)
		(unit 1)
		(exclude_from_sim no)
		(in_bom yes)
		(on_board yes)
		(dnp no)
		(fields_autoplaced yes)
		(property "Reference" "#PWR051"
			(at 44.45 233.68 0)
			(effects
				(font
					(size 1.27 1.27)
					(thickness 0.15)
				)
				(justify left bottom)
				(hide yes)
			)
		)
		(property "Value" "+1V8"
			(at 29.21 226.695 0)
			(effects
				(font
					(size 1.27 1.27)
					(thickness 0.15)
				)
			)
		)
		(property "Footprint" ""
			(at 44.45 238.76 0)
			(effects
				(font
					(size 1.27 1.27)
					(thickness 0.15)
				)
				(justify left bottom)
				(hide yes)
			)
		)
		(property "Datasheet" ""
			(at 44.45 241.3 0)
			(effects
				(font
					(size 1.27 1.27)
					(thickness 0.15)
				)
				(justify left bottom)
				(hide yes)
			)
		)
		(property "Description" ""
			(at 29.21 231.14 0)
			(effects
				(font
					(size 1.27 1.27)
				)
				(hide yes)
			)
		)
		(property "Author" "Antmicro"
			(at 44.45 236.22 0)
			(effects
				(font
					(size 1.27 1.27)
					(thickness 0.15)
				)
				(justify left bottom)
				(hide yes)
			)
		)
		(property "License" "Apache-2.0"
			(at 44.45 238.76 0)
			(effects
				(font
					(size 1.27 1.27)
					(thickness 0.15)
				)
				(justify left bottom)
				(hide yes)
			)
		)
		(pin "1"
		)
		(instances
			(project "data-center-rdimm-ddr5-tester"
				(path ""
					(reference "#PWR051")
					(unit 1)
				)
			)
		)
	)
	(symbol
		(lib_id "antmicropower:GND")
		(at 102.87 148.59 0)
		(unit 1)
		(exclude_from_sim no)
		(in_bom yes)
		(on_board yes)
		(dnp no)
		(fields_autoplaced yes)
		(property "Reference" "#PWR093"
			(at 102.87 154.94 0)
			(effects
				(font
					(size 1.27 1.27)
				)
				(hide yes)
			)
		)
		(property "Value" "GND"
			(at 100.965 153.035 0)
			(effects
				(font
					(size 1.27 1.27)
					(thickness 0.15)
				)
				(justify left bottom)
			)
		)
		(property "Footprint" ""
			(at 111.76 156.21 0)
			(effects
				(font
					(size 1.27 1.27)
					(thickness 0.15)
				)
				(justify left bottom)
				(hide yes)
			)
		)
		(property "Datasheet" ""
			(at 111.76 161.29 0)
			(effects
				(font
					(size 1.27 1.27)
					(thickness 0.15)
				)
				(justify left bottom)
				(hide yes)
			)
		)
		(property "Description" ""
			(at 102.87 148.59 0)
			(effects
				(font
					(size 1.27 1.27)
				)
				(hide yes)
			)
		)
		(property "Author" "Antmicro"
			(at 111.76 153.67 0)
			(effects
				(font
					(size 1.27 1.27)
					(thickness 0.15)
				)
				(justify left bottom)
				(hide yes)
			)
		)
		(property "License" "Apache-2.0"
			(at 111.76 156.21 0)
			(effects
				(font
					(size 1.27 1.27)
					(thickness 0.15)
				)
				(justify left bottom)
				(hide yes)
			)
		)
		(pin "1"
		)
		(instances
			(project "data-center-rdimm-ddr5-tester"
				(path ""
					(reference "#PWR093")
					(unit 1)
				)
			)
		)
	)
	(symbol
		(lib_id "antmicropower:PWR_FLAG")
		(at 269.24 113.03 0)
		(mirror y)
		(unit 1)
		(exclude_from_sim no)
		(in_bom yes)
		(on_board yes)
		(dnp no)
		(property "Reference" "#FLG06"
			(at 269.24 111.125 0)
			(effects
				(font
					(size 1.27 1.27)
				)
				(hide yes)
			)
		)
		(property "Value" "PWR_FLAG"
			(at 262.255 109.22 0)
			(effects
				(font
					(size 1.27 1.27)
				)
				(justify right)
			)
		)
		(property "Footprint" ""
			(at 269.24 113.03 0)
			(effects
				(font
					(size 1.27 1.27)
				)
				(hide yes)
			)
		)
		(property "Datasheet" ""
			(at 269.24 113.03 0)
			(effects
				(font
					(size 1.27 1.27)
				)
				(hide yes)
			)
		)
		(property "Description" ""
			(at 269.24 113.03 0)
			(effects
				(font
					(size 1.27 1.27)
				)
				(hide yes)
			)
		)
		(pin "1"
		)
		(instances
			(project "data-center-rdimm-ddr5-tester"
				(path ""
					(reference "#FLG06")
					(unit 1)
				)
			)
		)
	)
	(symbol
		(lib_id "antmicropower:GND")
		(at 336.55 175.26 0)
		(unit 1)
		(exclude_from_sim no)
		(in_bom yes)
		(on_board yes)
		(dnp no)
		(fields_autoplaced yes)
		(property "Reference" "#PWR0111"
			(at 336.55 181.61 0)
			(effects
				(font
					(size 1.27 1.27)
				)
				(hide yes)
			)
		)
		(property "Value" "GND"
			(at 334.645 179.705 0)
			(effects
				(font
					(size 1.27 1.27)
					(thickness 0.15)
				)
				(justify left bottom)
			)
		)
		(property "Footprint" ""
			(at 345.44 182.88 0)
			(effects
				(font
					(size 1.27 1.27)
					(thickness 0.15)
				)
				(justify left bottom)
				(hide yes)
			)
		)
		(property "Datasheet" ""
			(at 345.44 187.96 0)
			(effects
				(font
					(size 1.27 1.27)
					(thickness 0.15)
				)
				(justify left bottom)
				(hide yes)
			)
		)
		(property "Description" ""
			(at 336.55 175.26 0)
			(effects
				(font
					(size 1.27 1.27)
				)
				(hide yes)
			)
		)
		(property "Author" "Antmicro"
			(at 345.44 180.34 0)
			(effects
				(font
					(size 1.27 1.27)
					(thickness 0.15)
				)
				(justify left bottom)
				(hide yes)
			)
		)
		(property "License" "Apache-2.0"
			(at 345.44 182.88 0)
			(effects
				(font
					(size 1.27 1.27)
					(thickness 0.15)
				)
				(justify left bottom)
				(hide yes)
			)
		)
		(pin "1"
		)
		(instances
			(project "data-center-rdimm-ddr5-tester"
				(path ""
					(reference "#PWR0111")
					(unit 1)
				)
			)
		)
	)
	(symbol
		(lib_id "antmicropower:GND")
		(at 95.25 148.59 0)
		(unit 1)
		(exclude_from_sim no)
		(in_bom yes)
		(on_board yes)
		(dnp no)
		(fields_autoplaced yes)
		(property "Reference" "#PWR092"
			(at 95.25 154.94 0)
			(effects
				(font
					(size 1.27 1.27)
				)
				(hide yes)
			)
		)
		(property "Value" "GND"
			(at 93.345 153.035 0)
			(effects
				(font
					(size 1.27 1.27)
					(thickness 0.15)
				)
				(justify left bottom)
			)
		)
		(property "Footprint" ""
			(at 104.14 156.21 0)
			(effects
				(font
					(size 1.27 1.27)
					(thickness 0.15)
				)
				(justify left bottom)
				(hide yes)
			)
		)
		(property "Datasheet" ""
			(at 104.14 161.29 0)
			(effects
				(font
					(size 1.27 1.27)
					(thickness 0.15)
				)
				(justify left bottom)
				(hide yes)
			)
		)
		(property "Description" ""
			(at 95.25 148.59 0)
			(effects
				(font
					(size 1.27 1.27)
				)
				(hide yes)
			)
		)
		(property "Author" "Antmicro"
			(at 104.14 153.67 0)
			(effects
				(font
					(size 1.27 1.27)
					(thickness 0.15)
				)
				(justify left bottom)
				(hide yes)
			)
		)
		(property "License" "Apache-2.0"
			(at 104.14 156.21 0)
			(effects
				(font
					(size 1.27 1.27)
					(thickness 0.15)
				)
				(justify left bottom)
				(hide yes)
			)
		)
		(pin "1"
		)
		(instances
			(project "data-center-rdimm-ddr5-tester"
				(path ""
					(reference "#PWR092")
					(unit 1)
				)
			)
		)
	)
	(symbol
		(lib_id "antmicroCapacitors0402:C_4u7_0402")
		(at 339.09 59.69 270)
		(unit 1)
		(exclude_from_sim no)
		(in_bom yes)
		(on_board yes)
		(dnp no)
		(property "Reference" "C103"
			(at 339.09 59.69 90)
			(effects
				(font
					(size 1.27 1.27)
				)
				(justify left)
			)
		)
		(property "Value" "C_4u7_0402"
			(at 328.93 80.01 0)
			(effects
				(font
					(size 1.27 1.27)
					(thickness 0.15)
				)
				(justify left bottom)
				(hide yes)
			)
		)
		(property "Footprint" "antmicro-footprints:C_0402_1005Metric_EIA"
			(at 326.39 80.01 0)
			(effects
				(font
					(size 1.27 1.27)
					(thickness 0.15)
				)
				(justify left bottom)
				(hide yes)
			)
		)
		(property "Datasheet" "https://www.murata.com/products/productdetail?partno=GRM155R61A475MEAA%23"
			(at 323.85 80.01 0)
			(effects
				(font
					(size 1.27 1.27)
					(thickness 0.15)
				)
				(justify left bottom)
				(hide yes)
			)
		)
		(property "Description" ""
			(at 339.09 59.69 0)
			(effects
				(font
					(size 1.27 1.27)
				)
				(hide yes)
			)
		)
		(property "Manufacturer" "Murata"
			(at 318.77 80.01 0)
			(effects
				(font
					(size 1.27 1.27)
					(thickness 0.15)
				)
				(justify left bottom)
				(hide yes)
			)
		)
		(property "MPN" "GRM155R61A475MEAAD"
			(at 321.31 80.01 0)
			(effects
				(font
					(size 1.27 1.27)
					(thickness 0.15)
				)
				(justify left bottom)
				(hide yes)
			)
		)
		(property "Val" "4u7"
			(at 339.725 64.135 90)
			(effects
				(font
					(size 1.27 1.27)
					(thickness 0.15)
				)
				(justify left)
			)
		)
		(property "License" "Apache-2.0"
			(at 316.23 80.01 0)
			(effects
				(font
					(size 1.27 1.27)
					(thickness 0.15)
				)
				(justify left bottom)
				(hide yes)
			)
		)
		(property "Author" "Antmicro"
			(at 313.69 80.01 0)
			(effects
				(font
					(size 1.27 1.27)
					(thickness 0.15)
				)
				(justify left bottom)
				(hide yes)
			)
		)
		(property "Voltage" ""
			(at 311.15 80.01 0)
			(effects
				(font
					(size 1.27 1.27)
				)
				(justify left bottom)
				(hide yes)
			)
		)
		(property "Dielectric" ""
			(at 308.61 80.01 0)
			(effects
				(font
					(size 1.27 1.27)
				)
				(justify left bottom)
				(hide yes)
			)
		)
		(pin "1"
		)
		(pin "2"
		)
		(instances
			(project "data-center-rdimm-ddr5-tester"
				(path ""
					(reference "C103")
					(unit 1)
				)
			)
		)
	)
	(symbol
		(lib_id "antmicroCapacitors0402:C_10u_10V_0402")
		(at 127 66.04 90)
		(unit 1)
		(exclude_from_sim no)
		(in_bom yes)
		(on_board yes)
		(dnp no)
		(property "Reference" "C243"
			(at 128.905 62.23 90)
			(effects
				(font
					(size 1.27 1.27)
					(thickness 0.15)
				)
				(justify right)
			)
		)
		(property "Value" "C_10u_10V_0402"
			(at 137.16 45.72 0)
			(effects
				(font
					(size 1.27 1.27)
					(thickness 0.15)
				)
				(justify left bottom)
				(hide yes)
			)
		)
		(property "Footprint" "antmicro-footprints:C_0402_1005Metric_EIA"
			(at 139.7 45.72 0)
			(effects
				(font
					(size 1.27 1.27)
					(thickness 0.15)
				)
				(justify left bottom)
				(hide yes)
			)
		)
		(property "Datasheet" "https://www.murata.com/products/productdetail?partno=GRM155R61A106ME11%23"
			(at 142.24 45.72 0)
			(effects
				(font
					(size 1.27 1.27)
					(thickness 0.15)
				)
				(justify left bottom)
				(hide yes)
			)
		)
		(property "Description" ""
			(at 127 66.04 0)
			(effects
				(font
					(size 1.27 1.27)
				)
				(hide yes)
			)
		)
		(property "MPN" "GRM155R61A106ME11D"
			(at 144.78 45.72 0)
			(effects
				(font
					(size 1.27 1.27)
					(thickness 0.15)
				)
				(justify left bottom)
				(hide yes)
			)
		)
		(property "Manufacturer" "Murata"
			(at 147.32 45.72 0)
			(effects
				(font
					(size 1.27 1.27)
					(thickness 0.15)
				)
				(justify left bottom)
				(hide yes)
			)
		)
		(property "License" "Apache-2.0"
			(at 149.86 45.72 0)
			(effects
				(font
					(size 1.27 1.27)
					(thickness 0.15)
				)
				(justify left bottom)
				(hide yes)
			)
		)
		(property "Author" "Antmicro"
			(at 152.4 45.72 0)
			(effects
				(font
					(size 1.27 1.27)
					(thickness 0.15)
				)
				(justify left bottom)
				(hide yes)
			)
		)
		(property "Val" "10u"
			(at 128.905 64.77 90)
			(effects
				(font
					(size 1.27 1.27)
					(thickness 0.15)
				)
				(justify right)
			)
		)
		(property "Voltage" "10V"
			(at 154.94 45.72 0)
			(effects
				(font
					(size 1.27 1.27)
				)
				(justify left bottom)
				(hide yes)
			)
		)
		(property "Dielectric" "X5R"
			(at 157.48 45.72 0)
			(effects
				(font
					(size 1.27 1.27)
				)
				(justify left bottom)
				(hide yes)
			)
		)
		(pin "1"
		)
		(pin "2"
		)
		(instances
			(project "data-center-rdimm-ddr5-tester"
				(path ""
					(reference "C243")
					(unit 1)
				)
			)
		)
	)
	(symbol
		(lib_id "antmicroCapacitors0402:C_4u7_0402")
		(at 345.44 168.91 270)
		(unit 1)
		(exclude_from_sim no)
		(in_bom yes)
		(on_board yes)
		(dnp no)
		(property "Reference" "C97"
			(at 346.075 168.91 90)
			(effects
				(font
					(size 1.27 1.27)
				)
				(justify left)
			)
		)
		(property "Value" "C_4u7_0402"
			(at 335.28 189.23 0)
			(effects
				(font
					(size 1.27 1.27)
					(thickness 0.15)
				)
				(justify left bottom)
				(hide yes)
			)
		)
		(property "Footprint" "antmicro-footprints:C_0402_1005Metric_EIA"
			(at 332.74 189.23 0)
			(effects
				(font
					(size 1.27 1.27)
					(thickness 0.15)
				)
				(justify left bottom)
				(hide yes)
			)
		)
		(property "Datasheet" "https://www.murata.com/products/productdetail?partno=GRM155R61A475MEAA%23"
			(at 330.2 189.23 0)
			(effects
				(font
					(size 1.27 1.27)
					(thickness 0.15)
				)
				(justify left bottom)
				(hide yes)
			)
		)
		(property "Description" ""
			(at 345.44 168.91 0)
			(effects
				(font
					(size 1.27 1.27)
				)
				(hide yes)
			)
		)
		(property "Manufacturer" "Murata"
			(at 325.12 189.23 0)
			(effects
				(font
					(size 1.27 1.27)
					(thickness 0.15)
				)
				(justify left bottom)
				(hide yes)
			)
		)
		(property "MPN" "GRM155R61A475MEAAD"
			(at 327.66 189.23 0)
			(effects
				(font
					(size 1.27 1.27)
					(thickness 0.15)
				)
				(justify left bottom)
				(hide yes)
			)
		)
		(property "Val" "4u7"
			(at 347.98 173.3612 90)
			(effects
				(font
					(size 1.27 1.27)
					(thickness 0.15)
				)
				(justify left)
			)
		)
		(property "License" "Apache-2.0"
			(at 322.58 189.23 0)
			(effects
				(font
					(size 1.27 1.27)
					(thickness 0.15)
				)
				(justify left bottom)
				(hide yes)
			)
		)
		(property "Author" "Antmicro"
			(at 320.04 189.23 0)
			(effects
				(font
					(size 1.27 1.27)
					(thickness 0.15)
				)
				(justify left bottom)
				(hide yes)
			)
		)
		(property "Voltage" ""
			(at 317.5 189.23 0)
			(effects
				(font
					(size 1.27 1.27)
				)
				(justify left bottom)
				(hide yes)
			)
		)
		(property "Dielectric" ""
			(at 314.96 189.23 0)
			(effects
				(font
					(size 1.27 1.27)
				)
				(justify left bottom)
				(hide yes)
			)
		)
		(pin "1"
		)
		(pin "2"
		)
		(instances
			(project "data-center-rdimm-ddr5-tester"
				(path ""
					(reference "C97")
					(unit 1)
				)
			)
		)
	)
	(symbol
		(lib_id "antmicropower:GND")
		(at 60.96 173.99 0)
		(unit 1)
		(exclude_from_sim no)
		(in_bom yes)
		(on_board yes)
		(dnp no)
		(fields_autoplaced yes)
		(property "Reference" "#PWR0100"
			(at 60.96 180.34 0)
			(effects
				(font
					(size 1.27 1.27)
				)
				(hide yes)
			)
		)
		(property "Value" "GND"
			(at 59.055 178.435 0)
			(effects
				(font
					(size 1.27 1.27)
					(thickness 0.15)
				)
				(justify left bottom)
			)
		)
		(property "Footprint" ""
			(at 69.85 181.61 0)
			(effects
				(font
					(size 1.27 1.27)
					(thickness 0.15)
				)
				(justify left bottom)
				(hide yes)
			)
		)
		(property "Datasheet" ""
			(at 69.85 186.69 0)
			(effects
				(font
					(size 1.27 1.27)
					(thickness 0.15)
				)
				(justify left bottom)
				(hide yes)
			)
		)
		(property "Description" ""
			(at 60.96 173.99 0)
			(effects
				(font
					(size 1.27 1.27)
				)
				(hide yes)
			)
		)
		(property "Author" "Antmicro"
			(at 69.85 179.07 0)
			(effects
				(font
					(size 1.27 1.27)
					(thickness 0.15)
				)
				(justify left bottom)
				(hide yes)
			)
		)
		(property "License" "Apache-2.0"
			(at 69.85 181.61 0)
			(effects
				(font
					(size 1.27 1.27)
					(thickness 0.15)
				)
				(justify left bottom)
				(hide yes)
			)
		)
		(pin "1"
		)
		(instances
			(project "data-center-rdimm-ddr5-tester"
				(path ""
					(reference "#PWR0100")
					(unit 1)
				)
			)
		)
	)
	(symbol
		(lib_id "antmicroCapacitors0402:C_1u_25V_0402")
		(at 95.25 147.32 90)
		(unit 1)
		(exclude_from_sim no)
		(in_bom yes)
		(on_board yes)
		(dnp no)
		(fields_autoplaced yes)
		(property "Reference" "C45"
			(at 97.79 143.5036 90)
			(effects
				(font
					(size 1.27 1.27)
					(thickness 0.15)
				)
				(justify right)
			)
		)
		(property "Value" "C_1u_25V_0402"
			(at 105.41 127 0)
			(effects
				(font
					(size 1.27 1.27)
					(thickness 0.15)
				)
				(justify left bottom)
				(hide yes)
			)
		)
		(property "Footprint" "antmicro-footprints:C_0402_1005Metric_EIA"
			(at 107.95 127 0)
			(effects
				(font
					(size 1.27 1.27)
					(thickness 0.15)
				)
				(justify left bottom)
				(hide yes)
			)
		)
		(property "Datasheet" "https://www.murata.com/products/productdetail?partno=GRM155R61E105KE11%23"
			(at 110.49 127 0)
			(effects
				(font
					(size 1.27 1.27)
					(thickness 0.15)
				)
				(justify left bottom)
				(hide yes)
			)
		)
		(property "Description" ""
			(at 95.25 147.32 0)
			(effects
				(font
					(size 1.27 1.27)
				)
				(hide yes)
			)
		)
		(property "MPN" "GRM155R61E105KE11J"
			(at 113.03 127 0)
			(effects
				(font
					(size 1.27 1.27)
					(thickness 0.15)
				)
				(justify left bottom)
				(hide yes)
			)
		)
		(property "Manufacturer" "Murata"
			(at 115.57 127 0)
			(effects
				(font
					(size 1.27 1.27)
					(thickness 0.15)
				)
				(justify left bottom)
				(hide yes)
			)
		)
		(property "License" "Apache-2.0"
			(at 118.11 127 0)
			(effects
				(font
					(size 1.27 1.27)
					(thickness 0.15)
				)
				(justify left bottom)
				(hide yes)
			)
		)
		(property "Author" "Antmicro"
			(at 120.65 127 0)
			(effects
				(font
					(size 1.27 1.27)
					(thickness 0.15)
				)
				(justify left bottom)
				(hide yes)
			)
		)
		(property "Val" "1u"
			(at 97.79 146.0436 90)
			(effects
				(font
					(size 1.27 1.27)
					(thickness 0.15)
				)
				(justify right)
			)
		)
		(property "Voltage" "25V"
			(at 123.19 127 0)
			(effects
				(font
					(size 1.27 1.27)
				)
				(justify left bottom)
				(hide yes)
			)
		)
		(property "Dielectric" "X5R"
			(at 125.73 127 0)
			(effects
				(font
					(size 1.27 1.27)
				)
				(justify left bottom)
				(hide yes)
			)
		)
		(pin "1"
		)
		(pin "2"
		)
		(instances
			(project "data-center-rdimm-ddr5-tester"
				(path ""
					(reference "C45")
					(unit 1)
				)
			)
		)
	)
	(symbol
		(lib_id "antmicroCapacitors0402:C_100n_0402")
		(at 173.99 270.51 90)
		(unit 1)
		(exclude_from_sim no)
		(in_bom yes)
		(on_board yes)
		(dnp no)
		(property "Reference" "C76"
			(at 178.435 266.065 90)
			(effects
				(font
					(size 1.27 1.27)
					(thickness 0.15)
				)
				(justify left)
			)
		)
		(property "Value" "C_100n_0402"
			(at 184.15 250.19 0)
			(effects
				(font
					(size 1.27 1.27)
					(thickness 0.15)
				)
				(justify left bottom)
				(hide yes)
			)
		)
		(property "Footprint" "antmicro-footprints:C_0402_1005Metric_EIA"
			(at 186.69 250.19 0)
			(effects
				(font
					(size 1.27 1.27)
					(thickness 0.15)
				)
				(justify left bottom)
				(hide yes)
			)
		)
		(property "Datasheet" "https://www.murata.com/products/productdetail?partno=GRM155R61H104KE14%23"
			(at 189.23 250.19 0)
			(effects
				(font
					(size 1.27 1.27)
					(thickness 0.15)
				)
				(justify left bottom)
				(hide yes)
			)
		)
		(property "Description" ""
			(at 173.99 270.51 0)
			(effects
				(font
					(size 1.27 1.27)
				)
				(hide yes)
			)
		)
		(property "MPN" "GRM155R61H104KE14D"
			(at 191.77 250.19 0)
			(effects
				(font
					(size 1.27 1.27)
					(thickness 0.15)
				)
				(justify left bottom)
				(hide yes)
			)
		)
		(property "Manufacturer" "Murata"
			(at 194.31 250.19 0)
			(effects
				(font
					(size 1.27 1.27)
					(thickness 0.15)
				)
				(justify left bottom)
				(hide yes)
			)
		)
		(property "License" "Apache-2.0"
			(at 196.85 250.19 0)
			(effects
				(font
					(size 1.27 1.27)
					(thickness 0.15)
				)
				(justify left bottom)
				(hide yes)
			)
		)
		(property "Author" "Antmicro"
			(at 199.39 250.19 0)
			(effects
				(font
					(size 1.27 1.27)
					(thickness 0.15)
				)
				(justify left bottom)
				(hide yes)
			)
		)
		(property "Val" "100n"
			(at 179.705 269.875 90)
			(effects
				(font
					(size 1.27 1.27)
					(thickness 0.15)
				)
				(justify left)
			)
		)
		(property "Voltage" "50V"
			(at 201.93 250.19 0)
			(effects
				(font
					(size 1.27 1.27)
				)
				(justify left bottom)
				(hide yes)
			)
		)
		(property "Dielectric" "X5R"
			(at 204.47 250.19 0)
			(effects
				(font
					(size 1.27 1.27)
				)
				(justify left bottom)
				(hide yes)
			)
		)
		(pin "1"
		)
		(pin "2"
		)
		(instances
			(project "data-center-rdimm-ddr5-tester"
				(path ""
					(reference "C76")
					(unit 1)
				)
			)
		)
	)
	(symbol
		(lib_id "antmicroCapacitors0402:C_100n_0402")
		(at 368.3 64.77 90)
		(unit 1)
		(exclude_from_sim no)
		(in_bom yes)
		(on_board yes)
		(dnp no)
		(property "Reference" "C107"
			(at 368.935 60.325 90)
			(effects
				(font
					(size 1.27 1.27)
					(thickness 0.15)
				)
				(justify right)
			)
		)
		(property "Value" "C_100n_0402"
			(at 378.46 44.45 0)
			(effects
				(font
					(size 1.27 1.27)
					(thickness 0.15)
				)
				(justify left bottom)
				(hide yes)
			)
		)
		(property "Footprint" "antmicro-footprints:C_0402_1005Metric_EIA"
			(at 381 44.45 0)
			(effects
				(font
					(size 1.27 1.27)
					(thickness 0.15)
				)
				(justify left bottom)
				(hide yes)
			)
		)
		(property "Datasheet" "https://www.murata.com/products/productdetail?partno=GRM155R61H104KE14%23"
			(at 383.54 44.45 0)
			(effects
				(font
					(size 1.27 1.27)
					(thickness 0.15)
				)
				(justify left bottom)
				(hide yes)
			)
		)
		(property "Description" ""
			(at 368.3 64.77 0)
			(effects
				(font
					(size 1.27 1.27)
				)
				(hide yes)
			)
		)
		(property "MPN" "GRM155R61H104KE14D"
			(at 386.08 44.45 0)
			(effects
				(font
					(size 1.27 1.27)
					(thickness 0.15)
				)
				(justify left bottom)
				(hide yes)
			)
		)
		(property "Manufacturer" "Murata"
			(at 388.62 44.45 0)
			(effects
				(font
					(size 1.27 1.27)
					(thickness 0.15)
				)
				(justify left bottom)
				(hide yes)
			)
		)
		(property "License" "Apache-2.0"
			(at 391.16 44.45 0)
			(effects
				(font
					(size 1.27 1.27)
					(thickness 0.15)
				)
				(justify left bottom)
				(hide yes)
			)
		)
		(property "Author" "Antmicro"
			(at 393.7 44.45 0)
			(effects
				(font
					(size 1.27 1.27)
					(thickness 0.15)
				)
				(justify left bottom)
				(hide yes)
			)
		)
		(property "Val" "100n"
			(at 368.935 64.135 90)
			(effects
				(font
					(size 1.27 1.27)
					(thickness 0.15)
				)
				(justify right)
			)
		)
		(property "Voltage" "50V"
			(at 396.24 44.45 0)
			(effects
				(font
					(size 1.27 1.27)
				)
				(justify left bottom)
				(hide yes)
			)
		)
		(property "Dielectric" "X5R"
			(at 398.78 44.45 0)
			(effects
				(font
					(size 1.27 1.27)
				)
				(justify left bottom)
				(hide yes)
			)
		)
		(pin "1"
		)
		(pin "2"
		)
		(instances
			(project "data-center-rdimm-ddr5-tester"
				(path ""
					(reference "C107")
					(unit 1)
				)
			)
		)
	)
	(symbol
		(lib_id "antmicropower:GND")
		(at 78.74 173.99 0)
		(unit 1)
		(exclude_from_sim no)
		(in_bom yes)
		(on_board yes)
		(dnp no)
		(fields_autoplaced yes)
		(property "Reference" "#PWR0104"
			(at 78.74 180.34 0)
			(effects
				(font
					(size 1.27 1.27)
				)
				(hide yes)
			)
		)
		(property "Value" "GND"
			(at 76.835 178.435 0)
			(effects
				(font
					(size 1.27 1.27)
					(thickness 0.15)
				)
				(justify left bottom)
			)
		)
		(property "Footprint" ""
			(at 87.63 181.61 0)
			(effects
				(font
					(size 1.27 1.27)
					(thickness 0.15)
				)
				(justify left bottom)
				(hide yes)
			)
		)
		(property "Datasheet" ""
			(at 87.63 186.69 0)
			(effects
				(font
					(size 1.27 1.27)
					(thickness 0.15)
				)
				(justify left bottom)
				(hide yes)
			)
		)
		(property "Description" ""
			(at 78.74 173.99 0)
			(effects
				(font
					(size 1.27 1.27)
				)
				(hide yes)
			)
		)
		(property "Author" "Antmicro"
			(at 87.63 179.07 0)
			(effects
				(font
					(size 1.27 1.27)
					(thickness 0.15)
				)
				(justify left bottom)
				(hide yes)
			)
		)
		(property "License" "Apache-2.0"
			(at 87.63 181.61 0)
			(effects
				(font
					(size 1.27 1.27)
					(thickness 0.15)
				)
				(justify left bottom)
				(hide yes)
			)
		)
		(pin "1"
		)
		(instances
			(project "data-center-rdimm-ddr5-tester"
				(path ""
					(reference "#PWR0104")
					(unit 1)
				)
			)
		)
	)
	(symbol
		(lib_id "antmicropower:GND")
		(at 95.25 120.65 0)
		(unit 1)
		(exclude_from_sim no)
		(in_bom yes)
		(on_board yes)
		(dnp no)
		(fields_autoplaced yes)
		(property "Reference" "#PWR0109"
			(at 95.25 127 0)
			(effects
				(font
					(size 1.27 1.27)
				)
				(hide yes)
			)
		)
		(property "Value" "GND"
			(at 93.345 125.095 0)
			(effects
				(font
					(size 1.27 1.27)
					(thickness 0.15)
				)
				(justify left bottom)
			)
		)
		(property "Footprint" ""
			(at 104.14 128.27 0)
			(effects
				(font
					(size 1.27 1.27)
					(thickness 0.15)
				)
				(justify left bottom)
				(hide yes)
			)
		)
		(property "Datasheet" ""
			(at 104.14 133.35 0)
			(effects
				(font
					(size 1.27 1.27)
					(thickness 0.15)
				)
				(justify left bottom)
				(hide yes)
			)
		)
		(property "Description" ""
			(at 95.25 120.65 0)
			(effects
				(font
					(size 1.27 1.27)
				)
				(hide yes)
			)
		)
		(property "Author" "Antmicro"
			(at 104.14 125.73 0)
			(effects
				(font
					(size 1.27 1.27)
					(thickness 0.15)
				)
				(justify left bottom)
				(hide yes)
			)
		)
		(property "License" "Apache-2.0"
			(at 104.14 128.27 0)
			(effects
				(font
					(size 1.27 1.27)
					(thickness 0.15)
				)
				(justify left bottom)
				(hide yes)
			)
		)
		(pin "1"
		)
		(instances
			(project "data-center-rdimm-ddr5-tester"
				(path ""
					(reference "#PWR0109")
					(unit 1)
				)
			)
		)
	)
	(symbol
		(lib_id "antmicropower:GND")
		(at 44.45 93.98 0)
		(mirror y)
		(unit 1)
		(exclude_from_sim no)
		(in_bom yes)
		(on_board yes)
		(dnp no)
		(fields_autoplaced yes)
		(property "Reference" "#PWR0115"
			(at 44.45 100.33 0)
			(effects
				(font
					(size 1.27 1.27)
				)
				(hide yes)
			)
		)
		(property "Value" "GND"
			(at 46.355 98.425 0)
			(effects
				(font
					(size 1.27 1.27)
					(thickness 0.15)
				)
				(justify left bottom)
			)
		)
		(property "Footprint" ""
			(at 35.56 101.6 0)
			(effects
				(font
					(size 1.27 1.27)
					(thickness 0.15)
				)
				(justify left bottom)
				(hide yes)
			)
		)
		(property "Datasheet" ""
			(at 35.56 106.68 0)
			(effects
				(font
					(size 1.27 1.27)
					(thickness 0.15)
				)
				(justify left bottom)
				(hide yes)
			)
		)
		(property "Description" ""
			(at 44.45 93.98 0)
			(effects
				(font
					(size 1.27 1.27)
				)
				(hide yes)
			)
		)
		(property "Author" "Antmicro"
			(at 35.56 99.06 0)
			(effects
				(font
					(size 1.27 1.27)
					(thickness 0.15)
				)
				(justify left bottom)
				(hide yes)
			)
		)
		(property "License" "Apache-2.0"
			(at 35.56 101.6 0)
			(effects
				(font
					(size 1.27 1.27)
					(thickness 0.15)
				)
				(justify left bottom)
				(hide yes)
			)
		)
		(pin "1"
		)
		(instances
			(project "data-center-rdimm-ddr5-tester"
				(path ""
					(reference "#PWR0115")
					(unit 1)
				)
			)
		)
	)
	(symbol
		(lib_id "antmicroCapacitors0402:C_1u_25V_0402")
		(at 111.76 196.85 90)
		(unit 1)
		(exclude_from_sim no)
		(in_bom yes)
		(on_board yes)
		(dnp no)
		(fields_autoplaced yes)
		(property "Reference" "C248"
			(at 114.3 193.0336 90)
			(effects
				(font
					(size 1.27 1.27)
					(thickness 0.15)
				)
				(justify right)
			)
		)
		(property "Value" "C_1u_25V_0402"
			(at 121.92 176.53 0)
			(effects
				(font
					(size 1.27 1.27)
					(thickness 0.15)
				)
				(justify left bottom)
				(hide yes)
			)
		)
		(property "Footprint" "antmicro-footprints:C_0402_1005Metric_EIA"
			(at 124.46 176.53 0)
			(effects
				(font
					(size 1.27 1.27)
					(thickness 0.15)
				)
				(justify left bottom)
				(hide yes)
			)
		)
		(property "Datasheet" "https://www.murata.com/products/productdetail?partno=GRM155R61E105KE11%23"
			(at 127 176.53 0)
			(effects
				(font
					(size 1.27 1.27)
					(thickness 0.15)
				)
				(justify left bottom)
				(hide yes)
			)
		)
		(property "Description" ""
			(at 111.76 196.85 0)
			(effects
				(font
					(size 1.27 1.27)
				)
				(hide yes)
			)
		)
		(property "MPN" "GRM155R61E105KE11J"
			(at 129.54 176.53 0)
			(effects
				(font
					(size 1.27 1.27)
					(thickness 0.15)
				)
				(justify left bottom)
				(hide yes)
			)
		)
		(property "Manufacturer" "Murata"
			(at 132.08 176.53 0)
			(effects
				(font
					(size 1.27 1.27)
					(thickness 0.15)
				)
				(justify left bottom)
				(hide yes)
			)
		)
		(property "License" "Apache-2.0"
			(at 134.62 176.53 0)
			(effects
				(font
					(size 1.27 1.27)
					(thickness 0.15)
				)
				(justify left bottom)
				(hide yes)
			)
		)
		(property "Author" "Antmicro"
			(at 137.16 176.53 0)
			(effects
				(font
					(size 1.27 1.27)
					(thickness 0.15)
				)
				(justify left bottom)
				(hide yes)
			)
		)
		(property "Val" "1u"
			(at 114.3 195.5736 90)
			(effects
				(font
					(size 1.27 1.27)
					(thickness 0.15)
				)
				(justify right)
			)
		)
		(property "Voltage" "25V"
			(at 139.7 176.53 0)
			(effects
				(font
					(size 1.27 1.27)
				)
				(justify left bottom)
				(hide yes)
			)
		)
		(property "Dielectric" "X5R"
			(at 142.24 176.53 0)
			(effects
				(font
					(size 1.27 1.27)
				)
				(justify left bottom)
				(hide yes)
			)
		)
		(pin "1"
		)
		(pin "2"
		)
		(instances
			(project "data-center-rdimm-ddr5-tester"
				(path ""
					(reference "C248")
					(unit 1)
				)
			)
		)
	)
	(symbol
		(lib_id "antmicropower:GND")
		(at 332.74 101.6 0)
		(unit 1)
		(exclude_from_sim no)
		(in_bom yes)
		(on_board yes)
		(dnp no)
		(fields_autoplaced yes)
		(property "Reference" "#PWR0120"
			(at 332.74 107.95 0)
			(effects
				(font
					(size 1.27 1.27)
				)
				(hide yes)
			)
		)
		(property "Value" "GND"
			(at 330.835 106.045 0)
			(effects
				(font
					(size 1.27 1.27)
					(thickness 0.15)
				)
				(justify left bottom)
			)
		)
		(property "Footprint" ""
			(at 341.63 109.22 0)
			(effects
				(font
					(size 1.27 1.27)
					(thickness 0.15)
				)
				(justify left bottom)
				(hide yes)
			)
		)
		(property "Datasheet" ""
			(at 341.63 114.3 0)
			(effects
				(font
					(size 1.27 1.27)
					(thickness 0.15)
				)
				(justify left bottom)
				(hide yes)
			)
		)
		(property "Description" ""
			(at 332.74 101.6 0)
			(effects
				(font
					(size 1.27 1.27)
				)
				(hide yes)
			)
		)
		(property "Author" "Antmicro"
			(at 341.63 106.68 0)
			(effects
				(font
					(size 1.27 1.27)
					(thickness 0.15)
				)
				(justify left bottom)
				(hide yes)
			)
		)
		(property "License" "Apache-2.0"
			(at 341.63 109.22 0)
			(effects
				(font
					(size 1.27 1.27)
					(thickness 0.15)
				)
				(justify left bottom)
				(hide yes)
			)
		)
		(pin "1"
		)
		(instances
			(project "data-center-rdimm-ddr5-tester"
				(path ""
					(reference "#PWR0120")
					(unit 1)
				)
			)
		)
	)
	(symbol
		(lib_id "antmicroCapacitors0402:C_100n_0402")
		(at 69.85 119.38 90)
		(unit 1)
		(exclude_from_sim no)
		(in_bom yes)
		(on_board yes)
		(dnp no)
		(property "Reference" "C42"
			(at 70.485 114.935 90)
			(effects
				(font
					(size 1.27 1.27)
					(thickness 0.15)
				)
				(justify right)
			)
		)
		(property "Value" "C_100n_0402"
			(at 80.01 99.06 0)
			(effects
				(font
					(size 1.27 1.27)
					(thickness 0.15)
				)
				(justify left bottom)
				(hide yes)
			)
		)
		(property "Footprint" "antmicro-footprints:C_0402_1005Metric_EIA"
			(at 82.55 99.06 0)
			(effects
				(font
					(size 1.27 1.27)
					(thickness 0.15)
				)
				(justify left bottom)
				(hide yes)
			)
		)
		(property "Datasheet" "https://www.murata.com/products/productdetail?partno=GRM155R61H104KE14%23"
			(at 85.09 99.06 0)
			(effects
				(font
					(size 1.27 1.27)
					(thickness 0.15)
				)
				(justify left bottom)
				(hide yes)
			)
		)
		(property "Description" ""
			(at 69.85 119.38 0)
			(effects
				(font
					(size 1.27 1.27)
				)
				(hide yes)
			)
		)
		(property "MPN" "GRM155R61H104KE14D"
			(at 87.63 99.06 0)
			(effects
				(font
					(size 1.27 1.27)
					(thickness 0.15)
				)
				(justify left bottom)
				(hide yes)
			)
		)
		(property "Manufacturer" "Murata"
			(at 90.17 99.06 0)
			(effects
				(font
					(size 1.27 1.27)
					(thickness 0.15)
				)
				(justify left bottom)
				(hide yes)
			)
		)
		(property "License" "Apache-2.0"
			(at 92.71 99.06 0)
			(effects
				(font
					(size 1.27 1.27)
					(thickness 0.15)
				)
				(justify left bottom)
				(hide yes)
			)
		)
		(property "Author" "Antmicro"
			(at 95.25 99.06 0)
			(effects
				(font
					(size 1.27 1.27)
					(thickness 0.15)
				)
				(justify left bottom)
				(hide yes)
			)
		)
		(property "Val" "100n"
			(at 70.485 118.745 90)
			(effects
				(font
					(size 1.27 1.27)
					(thickness 0.15)
				)
				(justify right)
			)
		)
		(property "Voltage" "50V"
			(at 97.79 99.06 0)
			(effects
				(font
					(size 1.27 1.27)
				)
				(justify left bottom)
				(hide yes)
			)
		)
		(property "Dielectric" "X5R"
			(at 100.33 99.06 0)
			(effects
				(font
					(size 1.27 1.27)
				)
				(justify left bottom)
				(hide yes)
			)
		)
		(pin "1"
		)
		(pin "2"
		)
		(instances
			(project "data-center-rdimm-ddr5-tester"
				(path ""
					(reference "C42")
					(unit 1)
				)
			)
		)
	)
	(symbol
		(lib_id "antmicropower:GND")
		(at 104.14 198.12 0)
		(unit 1)
		(exclude_from_sim no)
		(in_bom yes)
		(on_board yes)
		(dnp no)
		(fields_autoplaced yes)
		(property "Reference" "#PWR0313"
			(at 104.14 204.47 0)
			(effects
				(font
					(size 1.27 1.27)
				)
				(hide yes)
			)
		)
		(property "Value" "GND"
			(at 102.235 202.565 0)
			(effects
				(font
					(size 1.27 1.27)
					(thickness 0.15)
				)
				(justify left bottom)
			)
		)
		(property "Footprint" ""
			(at 113.03 205.74 0)
			(effects
				(font
					(size 1.27 1.27)
					(thickness 0.15)
				)
				(justify left bottom)
				(hide yes)
			)
		)
		(property "Datasheet" ""
			(at 113.03 210.82 0)
			(effects
				(font
					(size 1.27 1.27)
					(thickness 0.15)
				)
				(justify left bottom)
				(hide yes)
			)
		)
		(property "Description" ""
			(at 104.14 198.12 0)
			(effects
				(font
					(size 1.27 1.27)
				)
				(hide yes)
			)
		)
		(property "Author" "Antmicro"
			(at 113.03 203.2 0)
			(effects
				(font
					(size 1.27 1.27)
					(thickness 0.15)
				)
				(justify left bottom)
				(hide yes)
			)
		)
		(property "License" "Apache-2.0"
			(at 113.03 205.74 0)
			(effects
				(font
					(size 1.27 1.27)
					(thickness 0.15)
				)
				(justify left bottom)
				(hide yes)
			)
		)
		(pin "1"
		)
		(instances
			(project "data-center-rdimm-ddr5-tester"
				(path ""
					(reference "#PWR0313")
					(unit 1)
				)
			)
		)
	)
	(symbol
		(lib_id "antmicroCapacitors0402:C_100n_0402")
		(at 340.36 100.33 90)
		(unit 1)
		(exclude_from_sim no)
		(in_bom yes)
		(on_board yes)
		(dnp no)
		(property "Reference" "C80"
			(at 340.995 95.885 90)
			(effects
				(font
					(size 1.27 1.27)
					(thickness 0.15)
				)
				(justify right)
			)
		)
		(property "Value" "C_100n_0402"
			(at 350.52 80.01 0)
			(effects
				(font
					(size 1.27 1.27)
					(thickness 0.15)
				)
				(justify left bottom)
				(hide yes)
			)
		)
		(property "Footprint" "antmicro-footprints:C_0402_1005Metric_EIA"
			(at 353.06 80.01 0)
			(effects
				(font
					(size 1.27 1.27)
					(thickness 0.15)
				)
				(justify left bottom)
				(hide yes)
			)
		)
		(property "Datasheet" "https://www.murata.com/products/productdetail?partno=GRM155R61H104KE14%23"
			(at 355.6 80.01 0)
			(effects
				(font
					(size 1.27 1.27)
					(thickness 0.15)
				)
				(justify left bottom)
				(hide yes)
			)
		)
		(property "Description" ""
			(at 340.36 100.33 0)
			(effects
				(font
					(size 1.27 1.27)
				)
				(hide yes)
			)
		)
		(property "MPN" "GRM155R61H104KE14D"
			(at 358.14 80.01 0)
			(effects
				(font
					(size 1.27 1.27)
					(thickness 0.15)
				)
				(justify left bottom)
				(hide yes)
			)
		)
		(property "Manufacturer" "Murata"
			(at 360.68 80.01 0)
			(effects
				(font
					(size 1.27 1.27)
					(thickness 0.15)
				)
				(justify left bottom)
				(hide yes)
			)
		)
		(property "License" "Apache-2.0"
			(at 363.22 80.01 0)
			(effects
				(font
					(size 1.27 1.27)
					(thickness 0.15)
				)
				(justify left bottom)
				(hide yes)
			)
		)
		(property "Author" "Antmicro"
			(at 365.76 80.01 0)
			(effects
				(font
					(size 1.27 1.27)
					(thickness 0.15)
				)
				(justify left bottom)
				(hide yes)
			)
		)
		(property "Val" "100n"
			(at 340.995 99.695 90)
			(effects
				(font
					(size 1.27 1.27)
					(thickness 0.15)
				)
				(justify right)
			)
		)
		(property "Voltage" "50V"
			(at 368.3 80.01 0)
			(effects
				(font
					(size 1.27 1.27)
				)
				(justify left bottom)
				(hide yes)
			)
		)
		(property "Dielectric" "X5R"
			(at 370.84 80.01 0)
			(effects
				(font
					(size 1.27 1.27)
				)
				(justify left bottom)
				(hide yes)
			)
		)
		(pin "1"
		)
		(pin "2"
		)
		(instances
			(project "data-center-rdimm-ddr5-tester"
				(path ""
					(reference "C80")
					(unit 1)
				)
			)
		)
	)
	(symbol
		(lib_id "antmicroCapacitors0402:C_1u_25V_0402")
		(at 60.96 172.72 90)
		(unit 1)
		(exclude_from_sim no)
		(in_bom yes)
		(on_board yes)
		(dnp no)
		(fields_autoplaced yes)
		(property "Reference" "C53"
			(at 63.5 168.9036 90)
			(effects
				(font
					(size 1.27 1.27)
					(thickness 0.15)
				)
				(justify right)
			)
		)
		(property "Value" "C_1u_25V_0402"
			(at 71.12 152.4 0)
			(effects
				(font
					(size 1.27 1.27)
					(thickness 0.15)
				)
				(justify left bottom)
				(hide yes)
			)
		)
		(property "Footprint" "antmicro-footprints:C_0402_1005Metric_EIA"
			(at 73.66 152.4 0)
			(effects
				(font
					(size 1.27 1.27)
					(thickness 0.15)
				)
				(justify left bottom)
				(hide yes)
			)
		)
		(property "Datasheet" "https://www.murata.com/products/productdetail?partno=GRM155R61E105KE11%23"
			(at 76.2 152.4 0)
			(effects
				(font
					(size 1.27 1.27)
					(thickness 0.15)
				)
				(justify left bottom)
				(hide yes)
			)
		)
		(property "Description" ""
			(at 60.96 172.72 0)
			(effects
				(font
					(size 1.27 1.27)
				)
				(hide yes)
			)
		)
		(property "MPN" "GRM155R61E105KE11J"
			(at 78.74 152.4 0)
			(effects
				(font
					(size 1.27 1.27)
					(thickness 0.15)
				)
				(justify left bottom)
				(hide yes)
			)
		)
		(property "Manufacturer" "Murata"
			(at 81.28 152.4 0)
			(effects
				(font
					(size 1.27 1.27)
					(thickness 0.15)
				)
				(justify left bottom)
				(hide yes)
			)
		)
		(property "License" "Apache-2.0"
			(at 83.82 152.4 0)
			(effects
				(font
					(size 1.27 1.27)
					(thickness 0.15)
				)
				(justify left bottom)
				(hide yes)
			)
		)
		(property "Author" "Antmicro"
			(at 86.36 152.4 0)
			(effects
				(font
					(size 1.27 1.27)
					(thickness 0.15)
				)
				(justify left bottom)
				(hide yes)
			)
		)
		(property "Val" "1u"
			(at 63.5 171.4436 90)
			(effects
				(font
					(size 1.27 1.27)
					(thickness 0.15)
				)
				(justify right)
			)
		)
		(property "Voltage" "25V"
			(at 88.9 152.4 0)
			(effects
				(font
					(size 1.27 1.27)
				)
				(justify left bottom)
				(hide yes)
			)
		)
		(property "Dielectric" "X5R"
			(at 91.44 152.4 0)
			(effects
				(font
					(size 1.27 1.27)
				)
				(justify left bottom)
				(hide yes)
			)
		)
		(pin "1"
		)
		(pin "2"
		)
		(instances
			(project "data-center-rdimm-ddr5-tester"
				(path ""
					(reference "C53")
					(unit 1)
				)
			)
		)
	)
	(symbol
		(lib_id "antmicroCapacitors0402:C_10u_10V_0402")
		(at 328.93 64.77 90)
		(unit 1)
		(exclude_from_sim no)
		(in_bom yes)
		(on_board yes)
		(dnp no)
		(property "Reference" "C167"
			(at 330.835 60.96 90)
			(effects
				(font
					(size 1.27 1.27)
					(thickness 0.15)
				)
				(justify right)
			)
		)
		(property "Value" "C_10u_10V_0402"
			(at 339.09 44.45 0)
			(effects
				(font
					(size 1.27 1.27)
					(thickness 0.15)
				)
				(justify left bottom)
				(hide yes)
			)
		)
		(property "Footprint" "antmicro-footprints:C_0402_1005Metric_EIA"
			(at 341.63 44.45 0)
			(effects
				(font
					(size 1.27 1.27)
					(thickness 0.15)
				)
				(justify left bottom)
				(hide yes)
			)
		)
		(property "Datasheet" "https://www.murata.com/products/productdetail?partno=GRM155R61A106ME11%23"
			(at 344.17 44.45 0)
			(effects
				(font
					(size 1.27 1.27)
					(thickness 0.15)
				)
				(justify left bottom)
				(hide yes)
			)
		)
		(property "Description" ""
			(at 328.93 64.77 0)
			(effects
				(font
					(size 1.27 1.27)
				)
				(hide yes)
			)
		)
		(property "MPN" "GRM155R61A106ME11D"
			(at 346.71 44.45 0)
			(effects
				(font
					(size 1.27 1.27)
					(thickness 0.15)
				)
				(justify left bottom)
				(hide yes)
			)
		)
		(property "Manufacturer" "Murata"
			(at 349.25 44.45 0)
			(effects
				(font
					(size 1.27 1.27)
					(thickness 0.15)
				)
				(justify left bottom)
				(hide yes)
			)
		)
		(property "License" "Apache-2.0"
			(at 351.79 44.45 0)
			(effects
				(font
					(size 1.27 1.27)
					(thickness 0.15)
				)
				(justify left bottom)
				(hide yes)
			)
		)
		(property "Author" "Antmicro"
			(at 354.33 44.45 0)
			(effects
				(font
					(size 1.27 1.27)
					(thickness 0.15)
				)
				(justify left bottom)
				(hide yes)
			)
		)
		(property "Val" "10u"
			(at 330.835 63.5 90)
			(effects
				(font
					(size 1.27 1.27)
					(thickness 0.15)
				)
				(justify right)
			)
		)
		(property "Voltage" "10V"
			(at 356.87 44.45 0)
			(effects
				(font
					(size 1.27 1.27)
				)
				(justify left bottom)
				(hide yes)
			)
		)
		(property "Dielectric" "X5R"
			(at 359.41 44.45 0)
			(effects
				(font
					(size 1.27 1.27)
				)
				(justify left bottom)
				(hide yes)
			)
		)
		(pin "1"
		)
		(pin "2"
		)
		(instances
			(project "data-center-rdimm-ddr5-tester"
				(path ""
					(reference "C167")
					(unit 1)
				)
			)
		)
	)
	(symbol
		(lib_id "antmicropower:GND")
		(at 322.58 66.04 0)
		(unit 1)
		(exclude_from_sim no)
		(in_bom yes)
		(on_board yes)
		(dnp no)
		(fields_autoplaced yes)
		(property "Reference" "#PWR078"
			(at 322.58 72.39 0)
			(effects
				(font
					(size 1.27 1.27)
				)
				(hide yes)
			)
		)
		(property "Value" "GND"
			(at 320.675 70.485 0)
			(effects
				(font
					(size 1.27 1.27)
					(thickness 0.15)
				)
				(justify left bottom)
			)
		)
		(property "Footprint" ""
			(at 331.47 73.66 0)
			(effects
				(font
					(size 1.27 1.27)
					(thickness 0.15)
				)
				(justify left bottom)
				(hide yes)
			)
		)
		(property "Datasheet" ""
			(at 331.47 78.74 0)
			(effects
				(font
					(size 1.27 1.27)
					(thickness 0.15)
				)
				(justify left bottom)
				(hide yes)
			)
		)
		(property "Description" ""
			(at 322.58 66.04 0)
			(effects
				(font
					(size 1.27 1.27)
				)
				(hide yes)
			)
		)
		(property "Author" "Antmicro"
			(at 331.47 71.12 0)
			(effects
				(font
					(size 1.27 1.27)
					(thickness 0.15)
				)
				(justify left bottom)
				(hide yes)
			)
		)
		(property "License" "Apache-2.0"
			(at 331.47 73.66 0)
			(effects
				(font
					(size 1.27 1.27)
					(thickness 0.15)
				)
				(justify left bottom)
				(hide yes)
			)
		)
		(pin "1"
		)
		(instances
			(project "data-center-rdimm-ddr5-tester"
				(path ""
					(reference "#PWR078")
					(unit 1)
				)
			)
		)
	)
	(symbol
		(lib_id "antmicropower:GND")
		(at 27.94 67.31 0)
		(mirror y)
		(unit 1)
		(exclude_from_sim no)
		(in_bom yes)
		(on_board yes)
		(dnp no)
		(fields_autoplaced yes)
		(property "Reference" "#PWR0121"
			(at 27.94 73.66 0)
			(effects
				(font
					(size 1.27 1.27)
				)
				(hide yes)
			)
		)
		(property "Value" "GND"
			(at 29.845 71.755 0)
			(effects
				(font
					(size 1.27 1.27)
					(thickness 0.15)
				)
				(justify left bottom)
			)
		)
		(property "Footprint" ""
			(at 19.05 74.93 0)
			(effects
				(font
					(size 1.27 1.27)
					(thickness 0.15)
				)
				(justify left bottom)
				(hide yes)
			)
		)
		(property "Datasheet" ""
			(at 19.05 80.01 0)
			(effects
				(font
					(size 1.27 1.27)
					(thickness 0.15)
				)
				(justify left bottom)
				(hide yes)
			)
		)
		(property "Description" ""
			(at 27.94 67.31 0)
			(effects
				(font
					(size 1.27 1.27)
				)
				(hide yes)
			)
		)
		(property "Author" "Antmicro"
			(at 19.05 72.39 0)
			(effects
				(font
					(size 1.27 1.27)
					(thickness 0.15)
				)
				(justify left bottom)
				(hide yes)
			)
		)
		(property "License" "Apache-2.0"
			(at 19.05 74.93 0)
			(effects
				(font
					(size 1.27 1.27)
					(thickness 0.15)
				)
				(justify left bottom)
				(hide yes)
			)
		)
		(pin "1"
		)
		(instances
			(project "data-center-rdimm-ddr5-tester"
				(path ""
					(reference "#PWR0121")
					(unit 1)
				)
			)
		)
	)
	(symbol
		(lib_id "antmicroCapacitors0402:C_1u_25V_0402")
		(at 58.42 241.3 90)
		(unit 1)
		(exclude_from_sim no)
		(in_bom yes)
		(on_board yes)
		(dnp no)
		(fields_autoplaced yes)
		(property "Reference" "C77"
			(at 60.96 237.4836 90)
			(effects
				(font
					(size 1.27 1.27)
					(thickness 0.15)
				)
				(justify right)
			)
		)
		(property "Value" "C_1u_25V_0402"
			(at 68.58 220.98 0)
			(effects
				(font
					(size 1.27 1.27)
					(thickness 0.15)
				)
				(justify left bottom)
				(hide yes)
			)
		)
		(property "Footprint" "antmicro-footprints:C_0402_1005Metric_EIA"
			(at 71.12 220.98 0)
			(effects
				(font
					(size 1.27 1.27)
					(thickness 0.15)
				)
				(justify left bottom)
				(hide yes)
			)
		)
		(property "Datasheet" "https://www.murata.com/products/productdetail?partno=GRM155R61E105KE11%23"
			(at 73.66 220.98 0)
			(effects
				(font
					(size 1.27 1.27)
					(thickness 0.15)
				)
				(justify left bottom)
				(hide yes)
			)
		)
		(property "Description" ""
			(at 58.42 241.3 0)
			(effects
				(font
					(size 1.27 1.27)
				)
				(hide yes)
			)
		)
		(property "MPN" "GRM155R61E105KE11J"
			(at 76.2 220.98 0)
			(effects
				(font
					(size 1.27 1.27)
					(thickness 0.15)
				)
				(justify left bottom)
				(hide yes)
			)
		)
		(property "Manufacturer" "Murata"
			(at 78.74 220.98 0)
			(effects
				(font
					(size 1.27 1.27)
					(thickness 0.15)
				)
				(justify left bottom)
				(hide yes)
			)
		)
		(property "License" "Apache-2.0"
			(at 81.28 220.98 0)
			(effects
				(font
					(size 1.27 1.27)
					(thickness 0.15)
				)
				(justify left bottom)
				(hide yes)
			)
		)
		(property "Author" "Antmicro"
			(at 83.82 220.98 0)
			(effects
				(font
					(size 1.27 1.27)
					(thickness 0.15)
				)
				(justify left bottom)
				(hide yes)
			)
		)
		(property "Val" "1u"
			(at 60.96 240.0236 90)
			(effects
				(font
					(size 1.27 1.27)
					(thickness 0.15)
				)
				(justify right)
			)
		)
		(property "Voltage" "25V"
			(at 86.36 220.98 0)
			(effects
				(font
					(size 1.27 1.27)
				)
				(justify left bottom)
				(hide yes)
			)
		)
		(property "Dielectric" "X5R"
			(at 88.9 220.98 0)
			(effects
				(font
					(size 1.27 1.27)
				)
				(justify left bottom)
				(hide yes)
			)
		)
		(pin "1"
		)
		(pin "2"
		)
		(instances
			(project "data-center-rdimm-ddr5-tester"
				(path ""
					(reference "C77")
					(unit 1)
				)
			)
		)
	)
	(symbol
		(lib_id "antmicropower:GND")
		(at 86.36 173.99 0)
		(unit 1)
		(exclude_from_sim no)
		(in_bom yes)
		(on_board yes)
		(dnp no)
		(fields_autoplaced yes)
		(property "Reference" "#PWR0105"
			(at 86.36 180.34 0)
			(effects
				(font
					(size 1.27 1.27)
				)
				(hide yes)
			)
		)
		(property "Value" "GND"
			(at 84.455 178.435 0)
			(effects
				(font
					(size 1.27 1.27)
					(thickness 0.15)
				)
				(justify left bottom)
			)
		)
		(property "Footprint" ""
			(at 95.25 181.61 0)
			(effects
				(font
					(size 1.27 1.27)
					(thickness 0.15)
				)
				(justify left bottom)
				(hide yes)
			)
		)
		(property "Datasheet" ""
			(at 95.25 186.69 0)
			(effects
				(font
					(size 1.27 1.27)
					(thickness 0.15)
				)
				(justify left bottom)
				(hide yes)
			)
		)
		(property "Description" ""
			(at 86.36 173.99 0)
			(effects
				(font
					(size 1.27 1.27)
				)
				(hide yes)
			)
		)
		(property "Author" "Antmicro"
			(at 95.25 179.07 0)
			(effects
				(font
					(size 1.27 1.27)
					(thickness 0.15)
				)
				(justify left bottom)
				(hide yes)
			)
		)
		(property "License" "Apache-2.0"
			(at 95.25 181.61 0)
			(effects
				(font
					(size 1.27 1.27)
					(thickness 0.15)
				)
				(justify left bottom)
				(hide yes)
			)
		)
		(pin "1"
		)
		(instances
			(project "data-center-rdimm-ddr5-tester"
				(path ""
					(reference "#PWR0105")
					(unit 1)
				)
			)
		)
	)
	(symbol
		(lib_id "antmicropower:GND")
		(at 78.74 198.12 0)
		(unit 1)
		(exclude_from_sim no)
		(in_bom yes)
		(on_board yes)
		(dnp no)
		(fields_autoplaced yes)
		(property "Reference" "#PWR0140"
			(at 78.74 204.47 0)
			(effects
				(font
					(size 1.27 1.27)
				)
				(hide yes)
			)
		)
		(property "Value" "GND"
			(at 76.835 202.565 0)
			(effects
				(font
					(size 1.27 1.27)
					(thickness 0.15)
				)
				(justify left bottom)
			)
		)
		(property "Footprint" ""
			(at 87.63 205.74 0)
			(effects
				(font
					(size 1.27 1.27)
					(thickness 0.15)
				)
				(justify left bottom)
				(hide yes)
			)
		)
		(property "Datasheet" ""
			(at 87.63 210.82 0)
			(effects
				(font
					(size 1.27 1.27)
					(thickness 0.15)
				)
				(justify left bottom)
				(hide yes)
			)
		)
		(property "Description" ""
			(at 78.74 198.12 0)
			(effects
				(font
					(size 1.27 1.27)
				)
				(hide yes)
			)
		)
		(property "Author" "Antmicro"
			(at 87.63 203.2 0)
			(effects
				(font
					(size 1.27 1.27)
					(thickness 0.15)
				)
				(justify left bottom)
				(hide yes)
			)
		)
		(property "License" "Apache-2.0"
			(at 87.63 205.74 0)
			(effects
				(font
					(size 1.27 1.27)
					(thickness 0.15)
				)
				(justify left bottom)
				(hide yes)
			)
		)
		(pin "1"
		)
		(instances
			(project "data-center-rdimm-ddr5-tester"
				(path ""
					(reference "#PWR0140")
					(unit 1)
				)
			)
		)
	)
	(symbol
		(lib_id "antmicroCapacitors0402:C_10u_10V_0402")
		(at 163.83 240.03 90)
		(unit 1)
		(exclude_from_sim no)
		(in_bom yes)
		(on_board yes)
		(dnp no)
		(property "Reference" "C37"
			(at 165.1 235.585 90)
			(effects
				(font
					(size 1.27 1.27)
					(thickness 0.15)
				)
				(justify right)
			)
		)
		(property "Value" "C_10u_10V_0402"
			(at 173.99 219.71 0)
			(effects
				(font
					(size 1.27 1.27)
					(thickness 0.15)
				)
				(justify left bottom)
				(hide yes)
			)
		)
		(property "Footprint" "antmicro-footprints:C_0402_1005Metric_EIA"
			(at 176.53 219.71 0)
			(effects
				(font
					(size 1.27 1.27)
					(thickness 0.15)
				)
				(justify left bottom)
				(hide yes)
			)
		)
		(property "Datasheet" "https://www.murata.com/products/productdetail?partno=GRM155R61A106ME11%23"
			(at 179.07 219.71 0)
			(effects
				(font
					(size 1.27 1.27)
					(thickness 0.15)
				)
				(justify left bottom)
				(hide yes)
			)
		)
		(property "Description" ""
			(at 163.83 240.03 0)
			(effects
				(font
					(size 1.27 1.27)
				)
				(hide yes)
			)
		)
		(property "MPN" "GRM155R61A106ME11D"
			(at 181.61 219.71 0)
			(effects
				(font
					(size 1.27 1.27)
					(thickness 0.15)
				)
				(justify left bottom)
				(hide yes)
			)
		)
		(property "Manufacturer" "Murata"
			(at 184.15 219.71 0)
			(effects
				(font
					(size 1.27 1.27)
					(thickness 0.15)
				)
				(justify left bottom)
				(hide yes)
			)
		)
		(property "License" "Apache-2.0"
			(at 186.69 219.71 0)
			(effects
				(font
					(size 1.27 1.27)
					(thickness 0.15)
				)
				(justify left bottom)
				(hide yes)
			)
		)
		(property "Author" "Antmicro"
			(at 189.23 219.71 0)
			(effects
				(font
					(size 1.27 1.27)
					(thickness 0.15)
				)
				(justify left bottom)
				(hide yes)
			)
		)
		(property "Val" "10u"
			(at 165.1 239.395 90)
			(effects
				(font
					(size 1.27 1.27)
					(thickness 0.15)
				)
				(justify right)
			)
		)
		(property "Voltage" "10V"
			(at 191.77 219.71 0)
			(effects
				(font
					(size 1.27 1.27)
				)
				(justify left bottom)
				(hide yes)
			)
		)
		(property "Dielectric" "X5R"
			(at 194.31 219.71 0)
			(effects
				(font
					(size 1.27 1.27)
				)
				(justify left bottom)
				(hide yes)
			)
		)
		(pin "1"
		)
		(pin "2"
		)
		(instances
			(project "data-center-rdimm-ddr5-tester"
				(path ""
					(reference "C37")
					(unit 1)
				)
			)
		)
	)
	(symbol
		(lib_id "antmicroCapacitors0402:C_1u_25V_0402")
		(at 78.74 172.72 90)
		(unit 1)
		(exclude_from_sim no)
		(in_bom yes)
		(on_board yes)
		(dnp no)
		(fields_autoplaced yes)
		(property "Reference" "C57"
			(at 81.28 168.9036 90)
			(effects
				(font
					(size 1.27 1.27)
					(thickness 0.15)
				)
				(justify right)
			)
		)
		(property "Value" "C_1u_25V_0402"
			(at 88.9 152.4 0)
			(effects
				(font
					(size 1.27 1.27)
					(thickness 0.15)
				)
				(justify left bottom)
				(hide yes)
			)
		)
		(property "Footprint" "antmicro-footprints:C_0402_1005Metric_EIA"
			(at 91.44 152.4 0)
			(effects
				(font
					(size 1.27 1.27)
					(thickness 0.15)
				)
				(justify left bottom)
				(hide yes)
			)
		)
		(property "Datasheet" "https://www.murata.com/products/productdetail?partno=GRM155R61E105KE11%23"
			(at 93.98 152.4 0)
			(effects
				(font
					(size 1.27 1.27)
					(thickness 0.15)
				)
				(justify left bottom)
				(hide yes)
			)
		)
		(property "Description" ""
			(at 78.74 172.72 0)
			(effects
				(font
					(size 1.27 1.27)
				)
				(hide yes)
			)
		)
		(property "MPN" "GRM155R61E105KE11J"
			(at 96.52 152.4 0)
			(effects
				(font
					(size 1.27 1.27)
					(thickness 0.15)
				)
				(justify left bottom)
				(hide yes)
			)
		)
		(property "Manufacturer" "Murata"
			(at 99.06 152.4 0)
			(effects
				(font
					(size 1.27 1.27)
					(thickness 0.15)
				)
				(justify left bottom)
				(hide yes)
			)
		)
		(property "License" "Apache-2.0"
			(at 101.6 152.4 0)
			(effects
				(font
					(size 1.27 1.27)
					(thickness 0.15)
				)
				(justify left bottom)
				(hide yes)
			)
		)
		(property "Author" "Antmicro"
			(at 104.14 152.4 0)
			(effects
				(font
					(size 1.27 1.27)
					(thickness 0.15)
				)
				(justify left bottom)
				(hide yes)
			)
		)
		(property "Val" "1u"
			(at 81.28 171.4436 90)
			(effects
				(font
					(size 1.27 1.27)
					(thickness 0.15)
				)
				(justify right)
			)
		)
		(property "Voltage" "25V"
			(at 106.68 152.4 0)
			(effects
				(font
					(size 1.27 1.27)
				)
				(justify left bottom)
				(hide yes)
			)
		)
		(property "Dielectric" "X5R"
			(at 109.22 152.4 0)
			(effects
				(font
					(size 1.27 1.27)
				)
				(justify left bottom)
				(hide yes)
			)
		)
		(pin "1"
		)
		(pin "2"
		)
		(instances
			(project "data-center-rdimm-ddr5-tester"
				(path ""
					(reference "C57")
					(unit 1)
				)
			)
		)
	)
	(symbol
		(lib_id "antmicroCapacitors0402:C_100n_0402")
		(at 111.76 119.38 90)
		(unit 1)
		(exclude_from_sim no)
		(in_bom yes)
		(on_board yes)
		(dnp no)
		(property "Reference" "C65"
			(at 112.395 114.935 90)
			(effects
				(font
					(size 1.27 1.27)
					(thickness 0.15)
				)
				(justify right)
			)
		)
		(property "Value" "C_100n_0402"
			(at 121.92 99.06 0)
			(effects
				(font
					(size 1.27 1.27)
					(thickness 0.15)
				)
				(justify left bottom)
				(hide yes)
			)
		)
		(property "Footprint" "antmicro-footprints:C_0402_1005Metric_EIA"
			(at 124.46 99.06 0)
			(effects
				(font
					(size 1.27 1.27)
					(thickness 0.15)
				)
				(justify left bottom)
				(hide yes)
			)
		)
		(property "Datasheet" "https://www.murata.com/products/productdetail?partno=GRM155R61H104KE14%23"
			(at 127 99.06 0)
			(effects
				(font
					(size 1.27 1.27)
					(thickness 0.15)
				)
				(justify left bottom)
				(hide yes)
			)
		)
		(property "Description" ""
			(at 111.76 119.38 0)
			(effects
				(font
					(size 1.27 1.27)
				)
				(hide yes)
			)
		)
		(property "MPN" "GRM155R61H104KE14D"
			(at 129.54 99.06 0)
			(effects
				(font
					(size 1.27 1.27)
					(thickness 0.15)
				)
				(justify left bottom)
				(hide yes)
			)
		)
		(property "Manufacturer" "Murata"
			(at 132.08 99.06 0)
			(effects
				(font
					(size 1.27 1.27)
					(thickness 0.15)
				)
				(justify left bottom)
				(hide yes)
			)
		)
		(property "License" "Apache-2.0"
			(at 134.62 99.06 0)
			(effects
				(font
					(size 1.27 1.27)
					(thickness 0.15)
				)
				(justify left bottom)
				(hide yes)
			)
		)
		(property "Author" "Antmicro"
			(at 137.16 99.06 0)
			(effects
				(font
					(size 1.27 1.27)
					(thickness 0.15)
				)
				(justify left bottom)
				(hide yes)
			)
		)
		(property "Val" "100n"
			(at 112.395 118.745 90)
			(effects
				(font
					(size 1.27 1.27)
					(thickness 0.15)
				)
				(justify right)
			)
		)
		(property "Voltage" "50V"
			(at 139.7 99.06 0)
			(effects
				(font
					(size 1.27 1.27)
				)
				(justify left bottom)
				(hide yes)
			)
		)
		(property "Dielectric" "X5R"
			(at 142.24 99.06 0)
			(effects
				(font
					(size 1.27 1.27)
				)
				(justify left bottom)
				(hide yes)
			)
		)
		(pin "1"
		)
		(pin "2"
		)
		(instances
			(project "data-center-rdimm-ddr5-tester"
				(path ""
					(reference "C65")
					(unit 1)
				)
			)
		)
	)
	(symbol
		(lib_id "antmicropower:GND")
		(at 49.53 67.31 0)
		(mirror y)
		(unit 1)
		(exclude_from_sim no)
		(in_bom yes)
		(on_board yes)
		(dnp no)
		(fields_autoplaced yes)
		(property "Reference" "#PWR077"
			(at 49.53 73.66 0)
			(effects
				(font
					(size 1.27 1.27)
				)
				(hide yes)
			)
		)
		(property "Value" "GND"
			(at 51.435 71.755 0)
			(effects
				(font
					(size 1.27 1.27)
					(thickness 0.15)
				)
				(justify left bottom)
			)
		)
		(property "Footprint" ""
			(at 40.64 74.93 0)
			(effects
				(font
					(size 1.27 1.27)
					(thickness 0.15)
				)
				(justify left bottom)
				(hide yes)
			)
		)
		(property "Datasheet" ""
			(at 40.64 80.01 0)
			(effects
				(font
					(size 1.27 1.27)
					(thickness 0.15)
				)
				(justify left bottom)
				(hide yes)
			)
		)
		(property "Description" ""
			(at 49.53 67.31 0)
			(effects
				(font
					(size 1.27 1.27)
				)
				(hide yes)
			)
		)
		(property "Author" "Antmicro"
			(at 40.64 72.39 0)
			(effects
				(font
					(size 1.27 1.27)
					(thickness 0.15)
				)
				(justify left bottom)
				(hide yes)
			)
		)
		(property "License" "Apache-2.0"
			(at 40.64 74.93 0)
			(effects
				(font
					(size 1.27 1.27)
					(thickness 0.15)
				)
				(justify left bottom)
				(hide yes)
			)
		)
		(pin "1"
		)
		(instances
			(project "data-center-rdimm-ddr5-tester"
				(path ""
					(reference "#PWR077")
					(unit 1)
				)
			)
		)
	)
	(symbol
		(lib_id "antmicroCapacitors0402:C_4u7_0402")
		(at 332.74 95.25 270)
		(unit 1)
		(exclude_from_sim no)
		(in_bom yes)
		(on_board yes)
		(dnp no)
		(property "Reference" "C72"
			(at 332.74 95.25 90)
			(effects
				(font
					(size 1.27 1.27)
				)
				(justify left)
			)
		)
		(property "Value" "C_4u7_0402"
			(at 322.58 115.57 0)
			(effects
				(font
					(size 1.27 1.27)
					(thickness 0.15)
				)
				(justify left bottom)
				(hide yes)
			)
		)
		(property "Footprint" "antmicro-footprints:C_0402_1005Metric_EIA"
			(at 320.04 115.57 0)
			(effects
				(font
					(size 1.27 1.27)
					(thickness 0.15)
				)
				(justify left bottom)
				(hide yes)
			)
		)
		(property "Datasheet" "https://www.murata.com/products/productdetail?partno=GRM155R61A475MEAA%23"
			(at 317.5 115.57 0)
			(effects
				(font
					(size 1.27 1.27)
					(thickness 0.15)
				)
				(justify left bottom)
				(hide yes)
			)
		)
		(property "Description" ""
			(at 332.74 95.25 0)
			(effects
				(font
					(size 1.27 1.27)
				)
				(hide yes)
			)
		)
		(property "Manufacturer" "Murata"
			(at 312.42 115.57 0)
			(effects
				(font
					(size 1.27 1.27)
					(thickness 0.15)
				)
				(justify left bottom)
				(hide yes)
			)
		)
		(property "MPN" "GRM155R61A475MEAAD"
			(at 314.96 115.57 0)
			(effects
				(font
					(size 1.27 1.27)
					(thickness 0.15)
				)
				(justify left bottom)
				(hide yes)
			)
		)
		(property "Val" "4u7"
			(at 333.375 99.695 90)
			(effects
				(font
					(size 1.27 1.27)
					(thickness 0.15)
				)
				(justify left)
			)
		)
		(property "License" "Apache-2.0"
			(at 309.88 115.57 0)
			(effects
				(font
					(size 1.27 1.27)
					(thickness 0.15)
				)
				(justify left bottom)
				(hide yes)
			)
		)
		(property "Author" "Antmicro"
			(at 307.34 115.57 0)
			(effects
				(font
					(size 1.27 1.27)
					(thickness 0.15)
				)
				(justify left bottom)
				(hide yes)
			)
		)
		(property "Voltage" ""
			(at 304.8 115.57 0)
			(effects
				(font
					(size 1.27 1.27)
				)
				(justify left bottom)
				(hide yes)
			)
		)
		(property "Dielectric" ""
			(at 302.26 115.57 0)
			(effects
				(font
					(size 1.27 1.27)
				)
				(justify left bottom)
				(hide yes)
			)
		)
		(pin "1"
		)
		(pin "2"
		)
		(instances
			(project "data-center-rdimm-ddr5-tester"
				(path ""
					(reference "C72")
					(unit 1)
				)
			)
		)
	)
	(symbol
		(lib_id "antmicroCapacitors0402:C_100n_0402")
		(at 177.8 240.03 90)
		(unit 1)
		(exclude_from_sim no)
		(in_bom yes)
		(on_board yes)
		(dnp no)
		(property "Reference" "C24"
			(at 178.435 235.585 90)
			(effects
				(font
					(size 1.27 1.27)
					(thickness 0.15)
				)
				(justify right)
			)
		)
		(property "Value" "C_100n_0402"
			(at 187.96 219.71 0)
			(effects
				(font
					(size 1.27 1.27)
					(thickness 0.15)
				)
				(justify left bottom)
				(hide yes)
			)
		)
		(property "Footprint" "antmicro-footprints:C_0402_1005Metric_EIA"
			(at 190.5 219.71 0)
			(effects
				(font
					(size 1.27 1.27)
					(thickness 0.15)
				)
				(justify left bottom)
				(hide yes)
			)
		)
		(property "Datasheet" "https://www.murata.com/products/productdetail?partno=GRM155R61H104KE14%23"
			(at 193.04 219.71 0)
			(effects
				(font
					(size 1.27 1.27)
					(thickness 0.15)
				)
				(justify left bottom)
				(hide yes)
			)
		)
		(property "Description" ""
			(at 177.8 240.03 0)
			(effects
				(font
					(size 1.27 1.27)
				)
				(hide yes)
			)
		)
		(property "MPN" "GRM155R61H104KE14D"
			(at 195.58 219.71 0)
			(effects
				(font
					(size 1.27 1.27)
					(thickness 0.15)
				)
				(justify left bottom)
				(hide yes)
			)
		)
		(property "Manufacturer" "Murata"
			(at 198.12 219.71 0)
			(effects
				(font
					(size 1.27 1.27)
					(thickness 0.15)
				)
				(justify left bottom)
				(hide yes)
			)
		)
		(property "License" "Apache-2.0"
			(at 200.66 219.71 0)
			(effects
				(font
					(size 1.27 1.27)
					(thickness 0.15)
				)
				(justify left bottom)
				(hide yes)
			)
		)
		(property "Author" "Antmicro"
			(at 203.2 219.71 0)
			(effects
				(font
					(size 1.27 1.27)
					(thickness 0.15)
				)
				(justify left bottom)
				(hide yes)
			)
		)
		(property "Val" "100n"
			(at 178.435 239.395 90)
			(effects
				(font
					(size 1.27 1.27)
					(thickness 0.15)
				)
				(justify right)
			)
		)
		(property "Voltage" "50V"
			(at 205.74 219.71 0)
			(effects
				(font
					(size 1.27 1.27)
				)
				(justify left bottom)
				(hide yes)
			)
		)
		(property "Dielectric" "X5R"
			(at 208.28 219.71 0)
			(effects
				(font
					(size 1.27 1.27)
				)
				(justify left bottom)
				(hide yes)
			)
		)
		(pin "1"
		)
		(pin "2"
		)
		(instances
			(project "data-center-rdimm-ddr5-tester"
				(path ""
					(reference "C24")
					(unit 1)
				)
			)
		)
	)
	(symbol
		(lib_id "antmicroCapacitors0603:C_47u_0603")
		(at 269.24 265.43 270)
		(unit 1)
		(exclude_from_sim no)
		(in_bom yes)
		(on_board yes)
		(dnp no)
		(property "Reference" "C22"
			(at 269.24 266.065 90)
			(effects
				(font
					(size 1.27 1.27)
				)
				(justify left)
			)
		)
		(property "Value" "C_47u_0603"
			(at 259.08 285.75 0)
			(effects
				(font
					(size 1.27 1.27)
					(thickness 0.15)
				)
				(justify left bottom)
				(hide yes)
			)
		)
		(property "Footprint" "antmicro-footprints:C_0603_1608Metric"
			(at 256.54 285.75 0)
			(effects
				(font
					(size 1.27 1.27)
					(thickness 0.15)
				)
				(justify left bottom)
				(hide yes)
			)
		)
		(property "Datasheet" "https://www.murata.com/products/productdetail?partno=GRM188R60J476ME15%23"
			(at 254 285.75 0)
			(effects
				(font
					(size 1.27 1.27)
					(thickness 0.15)
				)
				(justify left bottom)
				(hide yes)
			)
		)
		(property "Description" ""
			(at 269.24 265.43 0)
			(effects
				(font
					(size 1.27 1.27)
				)
				(hide yes)
			)
		)
		(property "Manufacturer" "Murata"
			(at 248.92 285.75 0)
			(effects
				(font
					(size 1.27 1.27)
					(thickness 0.15)
				)
				(justify left bottom)
				(hide yes)
			)
		)
		(property "MPN" "GRM188R60J476ME15D"
			(at 251.46 285.75 0)
			(effects
				(font
					(size 1.27 1.27)
					(thickness 0.15)
				)
				(justify left bottom)
				(hide yes)
			)
		)
		(property "Val" "47u"
			(at 269.24 269.875 90)
			(effects
				(font
					(size 1.27 1.27)
					(thickness 0.15)
				)
				(justify left)
			)
		)
		(property "License" "Apache-2.0"
			(at 246.38 285.75 0)
			(effects
				(font
					(size 1.27 1.27)
					(thickness 0.15)
				)
				(justify left bottom)
				(hide yes)
			)
		)
		(property "Author" "Antmicro"
			(at 243.84 285.75 0)
			(effects
				(font
					(size 1.27 1.27)
					(thickness 0.15)
				)
				(justify left bottom)
				(hide yes)
			)
		)
		(property "Voltage" ""
			(at 241.3 285.75 0)
			(effects
				(font
					(size 1.27 1.27)
				)
				(justify left bottom)
				(hide yes)
			)
		)
		(property "Dielectric" ""
			(at 238.76 285.75 0)
			(effects
				(font
					(size 1.27 1.27)
				)
				(justify left bottom)
				(hide yes)
			)
		)
		(pin "1"
		)
		(pin "2"
		)
		(instances
			(project "data-center-rdimm-ddr5-tester"
				(path ""
					(reference "C22")
					(unit 1)
				)
			)
		)
	)
	(symbol
		(lib_id "antmicropower:GND")
		(at 232.41 241.3 0)
		(unit 1)
		(exclude_from_sim no)
		(in_bom yes)
		(on_board yes)
		(dnp no)
		(fields_autoplaced yes)
		(property "Reference" "#PWR0127"
			(at 232.41 247.65 0)
			(effects
				(font
					(size 1.27 1.27)
				)
				(hide yes)
			)
		)
		(property "Value" "GND"
			(at 230.505 245.745 0)
			(effects
				(font
					(size 1.27 1.27)
					(thickness 0.15)
				)
				(justify left bottom)
			)
		)
		(property "Footprint" ""
			(at 241.3 248.92 0)
			(effects
				(font
					(size 1.27 1.27)
					(thickness 0.15)
				)
				(justify left bottom)
				(hide yes)
			)
		)
		(property "Datasheet" ""
			(at 241.3 254 0)
			(effects
				(font
					(size 1.27 1.27)
					(thickness 0.15)
				)
				(justify left bottom)
				(hide yes)
			)
		)
		(property "Description" ""
			(at 232.41 241.3 0)
			(effects
				(font
					(size 1.27 1.27)
				)
				(hide yes)
			)
		)
		(property "Author" "Antmicro"
			(at 241.3 246.38 0)
			(effects
				(font
					(size 1.27 1.27)
					(thickness 0.15)
				)
				(justify left bottom)
				(hide yes)
			)
		)
		(property "License" "Apache-2.0"
			(at 241.3 248.92 0)
			(effects
				(font
					(size 1.27 1.27)
					(thickness 0.15)
				)
				(justify left bottom)
				(hide yes)
			)
		)
		(pin "1"
		)
		(instances
			(project "data-center-rdimm-ddr5-tester"
				(path ""
					(reference "#PWR0127")
					(unit 1)
				)
			)
		)
	)
	(symbol
		(lib_id "antmicroCapacitors0402:C_100n_0402")
		(at 62.23 119.38 90)
		(unit 1)
		(exclude_from_sim no)
		(in_bom yes)
		(on_board yes)
		(dnp no)
		(property "Reference" "C33"
			(at 62.865 114.935 90)
			(effects
				(font
					(size 1.27 1.27)
					(thickness 0.15)
				)
				(justify right)
			)
		)
		(property "Value" "C_100n_0402"
			(at 72.39 99.06 0)
			(effects
				(font
					(size 1.27 1.27)
					(thickness 0.15)
				)
				(justify left bottom)
				(hide yes)
			)
		)
		(property "Footprint" "antmicro-footprints:C_0402_1005Metric_EIA"
			(at 74.93 99.06 0)
			(effects
				(font
					(size 1.27 1.27)
					(thickness 0.15)
				)
				(justify left bottom)
				(hide yes)
			)
		)
		(property "Datasheet" "https://www.murata.com/products/productdetail?partno=GRM155R61H104KE14%23"
			(at 77.47 99.06 0)
			(effects
				(font
					(size 1.27 1.27)
					(thickness 0.15)
				)
				(justify left bottom)
				(hide yes)
			)
		)
		(property "Description" ""
			(at 62.23 119.38 0)
			(effects
				(font
					(size 1.27 1.27)
				)
				(hide yes)
			)
		)
		(property "MPN" "GRM155R61H104KE14D"
			(at 80.01 99.06 0)
			(effects
				(font
					(size 1.27 1.27)
					(thickness 0.15)
				)
				(justify left bottom)
				(hide yes)
			)
		)
		(property "Manufacturer" "Murata"
			(at 82.55 99.06 0)
			(effects
				(font
					(size 1.27 1.27)
					(thickness 0.15)
				)
				(justify left bottom)
				(hide yes)
			)
		)
		(property "License" "Apache-2.0"
			(at 85.09 99.06 0)
			(effects
				(font
					(size 1.27 1.27)
					(thickness 0.15)
				)
				(justify left bottom)
				(hide yes)
			)
		)
		(property "Author" "Antmicro"
			(at 87.63 99.06 0)
			(effects
				(font
					(size 1.27 1.27)
					(thickness 0.15)
				)
				(justify left bottom)
				(hide yes)
			)
		)
		(property "Val" "100n"
			(at 62.865 118.745 90)
			(effects
				(font
					(size 1.27 1.27)
					(thickness 0.15)
				)
				(justify right)
			)
		)
		(property "Voltage" "50V"
			(at 90.17 99.06 0)
			(effects
				(font
					(size 1.27 1.27)
				)
				(justify left bottom)
				(hide yes)
			)
		)
		(property "Dielectric" "X5R"
			(at 92.71 99.06 0)
			(effects
				(font
					(size 1.27 1.27)
				)
				(justify left bottom)
				(hide yes)
			)
		)
		(pin "1"
		)
		(pin "2"
		)
		(instances
			(project "data-center-rdimm-ddr5-tester"
				(path ""
					(reference "C33")
					(unit 1)
				)
			)
		)
	)
	(symbol
		(lib_id "antmicroCapacitors0402:C_10u_10V_0402")
		(at 325.12 100.33 90)
		(unit 1)
		(exclude_from_sim no)
		(in_bom yes)
		(on_board yes)
		(dnp no)
		(property "Reference" "C70"
			(at 327.025 96.52 90)
			(effects
				(font
					(size 1.27 1.27)
					(thickness 0.15)
				)
				(justify right)
			)
		)
		(property "Value" "C_10u_10V_0402"
			(at 335.28 80.01 0)
			(effects
				(font
					(size 1.27 1.27)
					(thickness 0.15)
				)
				(justify left bottom)
				(hide yes)
			)
		)
		(property "Footprint" "antmicro-footprints:C_0402_1005Metric_EIA"
			(at 337.82 80.01 0)
			(effects
				(font
					(size 1.27 1.27)
					(thickness 0.15)
				)
				(justify left bottom)
				(hide yes)
			)
		)
		(property "Datasheet" "https://www.murata.com/products/productdetail?partno=GRM155R61A106ME11%23"
			(at 340.36 80.01 0)
			(effects
				(font
					(size 1.27 1.27)
					(thickness 0.15)
				)
				(justify left bottom)
				(hide yes)
			)
		)
		(property "Description" ""
			(at 325.12 100.33 0)
			(effects
				(font
					(size 1.27 1.27)
				)
				(hide yes)
			)
		)
		(property "MPN" "GRM155R61A106ME11D"
			(at 342.9 80.01 0)
			(effects
				(font
					(size 1.27 1.27)
					(thickness 0.15)
				)
				(justify left bottom)
				(hide yes)
			)
		)
		(property "Manufacturer" "Murata"
			(at 345.44 80.01 0)
			(effects
				(font
					(size 1.27 1.27)
					(thickness 0.15)
				)
				(justify left bottom)
				(hide yes)
			)
		)
		(property "License" "Apache-2.0"
			(at 347.98 80.01 0)
			(effects
				(font
					(size 1.27 1.27)
					(thickness 0.15)
				)
				(justify left bottom)
				(hide yes)
			)
		)
		(property "Author" "Antmicro"
			(at 350.52 80.01 0)
			(effects
				(font
					(size 1.27 1.27)
					(thickness 0.15)
				)
				(justify left bottom)
				(hide yes)
			)
		)
		(property "Val" "10u"
			(at 327.025 99.06 90)
			(effects
				(font
					(size 1.27 1.27)
					(thickness 0.15)
				)
				(justify right)
			)
		)
		(property "Voltage" "10V"
			(at 353.06 80.01 0)
			(effects
				(font
					(size 1.27 1.27)
				)
				(justify left bottom)
				(hide yes)
			)
		)
		(property "Dielectric" "X5R"
			(at 355.6 80.01 0)
			(effects
				(font
					(size 1.27 1.27)
				)
				(justify left bottom)
				(hide yes)
			)
		)
		(pin "1"
		)
		(pin "2"
		)
		(instances
			(project "data-center-rdimm-ddr5-tester"
				(path ""
					(reference "C70")
					(unit 1)
				)
			)
		)
	)
	(symbol
		(lib_id "antmicropower:+1V2_MGTAVTT")
		(at 339.09 55.88 0)
		(unit 1)
		(exclude_from_sim no)
		(in_bom yes)
		(on_board yes)
		(dnp no)
		(fields_autoplaced yes)
		(property "Reference" "#PWR0160"
			(at 339.09 59.69 0)
			(effects
				(font
					(size 1.27 1.27)
				)
				(hide yes)
			)
		)
		(property "Value" "+1V2_MGTAVTT"
			(at 339.09 52.07 0)
			(effects
				(font
					(size 1.27 1.27)
				)
			)
		)
		(property "Footprint" ""
			(at 339.09 55.88 0)
			(effects
				(font
					(size 1.27 1.27)
				)
				(hide yes)
			)
		)
		(property "Datasheet" ""
			(at 339.09 55.88 0)
			(effects
				(font
					(size 1.27 1.27)
				)
				(hide yes)
			)
		)
		(property "Description" ""
			(at 339.09 55.88 0)
			(effects
				(font
					(size 1.27 1.27)
				)
				(hide yes)
			)
		)
		(pin "1"
		)
		(instances
			(project "data-center-rdimm-ddr5-tester"
				(path ""
					(reference "#PWR0160")
					(unit 1)
				)
			)
		)
	)
	(symbol
		(lib_id "antmicroCapacitors0402:C_1u_25V_0402")
		(at 86.36 147.32 90)
		(unit 1)
		(exclude_from_sim no)
		(in_bom yes)
		(on_board yes)
		(dnp no)
		(fields_autoplaced yes)
		(property "Reference" "C43"
			(at 88.9 143.5036 90)
			(effects
				(font
					(size 1.27 1.27)
					(thickness 0.15)
				)
				(justify right)
			)
		)
		(property "Value" "C_1u_25V_0402"
			(at 96.52 127 0)
			(effects
				(font
					(size 1.27 1.27)
					(thickness 0.15)
				)
				(justify left bottom)
				(hide yes)
			)
		)
		(property "Footprint" "antmicro-footprints:C_0402_1005Metric_EIA"
			(at 99.06 127 0)
			(effects
				(font
					(size 1.27 1.27)
					(thickness 0.15)
				)
				(justify left bottom)
				(hide yes)
			)
		)
		(property "Datasheet" "https://www.murata.com/products/productdetail?partno=GRM155R61E105KE11%23"
			(at 101.6 127 0)
			(effects
				(font
					(size 1.27 1.27)
					(thickness 0.15)
				)
				(justify left bottom)
				(hide yes)
			)
		)
		(property "Description" ""
			(at 86.36 147.32 0)
			(effects
				(font
					(size 1.27 1.27)
				)
				(hide yes)
			)
		)
		(property "MPN" "GRM155R61E105KE11J"
			(at 104.14 127 0)
			(effects
				(font
					(size 1.27 1.27)
					(thickness 0.15)
				)
				(justify left bottom)
				(hide yes)
			)
		)
		(property "Manufacturer" "Murata"
			(at 106.68 127 0)
			(effects
				(font
					(size 1.27 1.27)
					(thickness 0.15)
				)
				(justify left bottom)
				(hide yes)
			)
		)
		(property "License" "Apache-2.0"
			(at 109.22 127 0)
			(effects
				(font
					(size 1.27 1.27)
					(thickness 0.15)
				)
				(justify left bottom)
				(hide yes)
			)
		)
		(property "Author" "Antmicro"
			(at 111.76 127 0)
			(effects
				(font
					(size 1.27 1.27)
					(thickness 0.15)
				)
				(justify left bottom)
				(hide yes)
			)
		)
		(property "Val" "1u"
			(at 88.9 146.0436 90)
			(effects
				(font
					(size 1.27 1.27)
					(thickness 0.15)
				)
				(justify right)
			)
		)
		(property "Voltage" "25V"
			(at 114.3 127 0)
			(effects
				(font
					(size 1.27 1.27)
				)
				(justify left bottom)
				(hide yes)
			)
		)
		(property "Dielectric" "X5R"
			(at 116.84 127 0)
			(effects
				(font
					(size 1.27 1.27)
				)
				(justify left bottom)
				(hide yes)
			)
		)
		(pin "1"
		)
		(pin "2"
		)
		(instances
			(project "data-center-rdimm-ddr5-tester"
				(path ""
					(reference "C43")
					(unit 1)
				)
			)
		)
	)
	(symbol
		(lib_id "antmicroCapacitors0402:C_10u_10V_0402")
		(at 330.2 133.35 90)
		(unit 1)
		(exclude_from_sim no)
		(in_bom yes)
		(on_board yes)
		(dnp no)
		(property "Reference" "C168"
			(at 332.105 129.54 90)
			(effects
				(font
					(size 1.27 1.27)
					(thickness 0.15)
				)
				(justify right)
			)
		)
		(property "Value" "C_10u_10V_0402"
			(at 340.36 113.03 0)
			(effects
				(font
					(size 1.27 1.27)
					(thickness 0.15)
				)
				(justify left bottom)
				(hide yes)
			)
		)
		(property "Footprint" "antmicro-footprints:C_0402_1005Metric_EIA"
			(at 342.9 113.03 0)
			(effects
				(font
					(size 1.27 1.27)
					(thickness 0.15)
				)
				(justify left bottom)
				(hide yes)
			)
		)
		(property "Datasheet" "https://www.murata.com/products/productdetail?partno=GRM155R61A106ME11%23"
			(at 345.44 113.03 0)
			(effects
				(font
					(size 1.27 1.27)
					(thickness 0.15)
				)
				(justify left bottom)
				(hide yes)
			)
		)
		(property "Description" ""
			(at 330.2 133.35 0)
			(effects
				(font
					(size 1.27 1.27)
				)
				(hide yes)
			)
		)
		(property "MPN" "GRM155R61A106ME11D"
			(at 347.98 113.03 0)
			(effects
				(font
					(size 1.27 1.27)
					(thickness 0.15)
				)
				(justify left bottom)
				(hide yes)
			)
		)
		(property "Manufacturer" "Murata"
			(at 350.52 113.03 0)
			(effects
				(font
					(size 1.27 1.27)
					(thickness 0.15)
				)
				(justify left bottom)
				(hide yes)
			)
		)
		(property "License" "Apache-2.0"
			(at 353.06 113.03 0)
			(effects
				(font
					(size 1.27 1.27)
					(thickness 0.15)
				)
				(justify left bottom)
				(hide yes)
			)
		)
		(property "Author" "Antmicro"
			(at 355.6 113.03 0)
			(effects
				(font
					(size 1.27 1.27)
					(thickness 0.15)
				)
				(justify left bottom)
				(hide yes)
			)
		)
		(property "Val" "10u"
			(at 332.105 132.08 90)
			(effects
				(font
					(size 1.27 1.27)
					(thickness 0.15)
				)
				(justify right)
			)
		)
		(property "Voltage" "10V"
			(at 358.14 113.03 0)
			(effects
				(font
					(size 1.27 1.27)
				)
				(justify left bottom)
				(hide yes)
			)
		)
		(property "Dielectric" "X5R"
			(at 360.68 113.03 0)
			(effects
				(font
					(size 1.27 1.27)
				)
				(justify left bottom)
				(hide yes)
			)
		)
		(pin "1"
		)
		(pin "2"
		)
		(instances
			(project "data-center-rdimm-ddr5-tester"
				(path ""
					(reference "C168")
					(unit 1)
				)
			)
		)
	)
	(symbol
		(lib_id "antmicropower:GND")
		(at 36.83 148.59 0)
		(unit 1)
		(exclude_from_sim no)
		(in_bom yes)
		(on_board yes)
		(dnp no)
		(fields_autoplaced yes)
		(property "Reference" "#PWR081"
			(at 36.83 154.94 0)
			(effects
				(font
					(size 1.27 1.27)
				)
				(hide yes)
			)
		)
		(property "Value" "GND"
			(at 34.925 153.035 0)
			(effects
				(font
					(size 1.27 1.27)
					(thickness 0.15)
				)
				(justify left bottom)
			)
		)
		(property "Footprint" ""
			(at 45.72 156.21 0)
			(effects
				(font
					(size 1.27 1.27)
					(thickness 0.15)
				)
				(justify left bottom)
				(hide yes)
			)
		)
		(property "Datasheet" ""
			(at 45.72 161.29 0)
			(effects
				(font
					(size 1.27 1.27)
					(thickness 0.15)
				)
				(justify left bottom)
				(hide yes)
			)
		)
		(property "Description" ""
			(at 36.83 148.59 0)
			(effects
				(font
					(size 1.27 1.27)
				)
				(hide yes)
			)
		)
		(property "Author" "Antmicro"
			(at 45.72 153.67 0)
			(effects
				(font
					(size 1.27 1.27)
					(thickness 0.15)
				)
				(justify left bottom)
				(hide yes)
			)
		)
		(property "License" "Apache-2.0"
			(at 45.72 156.21 0)
			(effects
				(font
					(size 1.27 1.27)
					(thickness 0.15)
				)
				(justify left bottom)
				(hide yes)
			)
		)
		(pin "1"
		)
		(instances
			(project "data-center-rdimm-ddr5-tester"
				(path ""
					(reference "#PWR081")
					(unit 1)
				)
			)
		)
	)
	(symbol
		(lib_id "antmicroCapacitors0402:C_1u_25V_0402")
		(at 67.31 241.3 90)
		(unit 1)
		(exclude_from_sim no)
		(in_bom yes)
		(on_board yes)
		(dnp no)
		(fields_autoplaced yes)
		(property "Reference" "C81"
			(at 69.85 237.4836 90)
			(effects
				(font
					(size 1.27 1.27)
					(thickness 0.15)
				)
				(justify right)
			)
		)
		(property "Value" "C_1u_25V_0402"
			(at 77.47 220.98 0)
			(effects
				(font
					(size 1.27 1.27)
					(thickness 0.15)
				)
				(justify left bottom)
				(hide yes)
			)
		)
		(property "Footprint" "antmicro-footprints:C_0402_1005Metric_EIA"
			(at 80.01 220.98 0)
			(effects
				(font
					(size 1.27 1.27)
					(thickness 0.15)
				)
				(justify left bottom)
				(hide yes)
			)
		)
		(property "Datasheet" "https://www.murata.com/products/productdetail?partno=GRM155R61E105KE11%23"
			(at 82.55 220.98 0)
			(effects
				(font
					(size 1.27 1.27)
					(thickness 0.15)
				)
				(justify left bottom)
				(hide yes)
			)
		)
		(property "Description" ""
			(at 67.31 241.3 0)
			(effects
				(font
					(size 1.27 1.27)
				)
				(hide yes)
			)
		)
		(property "MPN" "GRM155R61E105KE11J"
			(at 85.09 220.98 0)
			(effects
				(font
					(size 1.27 1.27)
					(thickness 0.15)
				)
				(justify left bottom)
				(hide yes)
			)
		)
		(property "Manufacturer" "Murata"
			(at 87.63 220.98 0)
			(effects
				(font
					(size 1.27 1.27)
					(thickness 0.15)
				)
				(justify left bottom)
				(hide yes)
			)
		)
		(property "License" "Apache-2.0"
			(at 90.17 220.98 0)
			(effects
				(font
					(size 1.27 1.27)
					(thickness 0.15)
				)
				(justify left bottom)
				(hide yes)
			)
		)
		(property "Author" "Antmicro"
			(at 92.71 220.98 0)
			(effects
				(font
					(size 1.27 1.27)
					(thickness 0.15)
				)
				(justify left bottom)
				(hide yes)
			)
		)
		(property "Val" "1u"
			(at 69.85 240.0236 90)
			(effects
				(font
					(size 1.27 1.27)
					(thickness 0.15)
				)
				(justify right)
			)
		)
		(property "Voltage" "25V"
			(at 95.25 220.98 0)
			(effects
				(font
					(size 1.27 1.27)
				)
				(justify left bottom)
				(hide yes)
			)
		)
		(property "Dielectric" "X5R"
			(at 97.79 220.98 0)
			(effects
				(font
					(size 1.27 1.27)
				)
				(justify left bottom)
				(hide yes)
			)
		)
		(pin "1"
		)
		(pin "2"
		)
		(instances
			(project "data-center-rdimm-ddr5-tester"
				(path ""
					(reference "C81")
					(unit 1)
				)
			)
		)
	)
	(symbol
		(lib_id "antmicroCapacitors0402:C_100n_0402")
		(at 276.86 238.76 90)
		(unit 1)
		(exclude_from_sim no)
		(in_bom yes)
		(on_board yes)
		(dnp no)
		(property "Reference" "C91"
			(at 277.495 234.315 90)
			(effects
				(font
					(size 1.27 1.27)
					(thickness 0.15)
				)
				(justify right)
			)
		)
		(property "Value" "C_100n_0402"
			(at 287.02 218.44 0)
			(effects
				(font
					(size 1.27 1.27)
					(thickness 0.15)
				)
				(justify left bottom)
				(hide yes)
			)
		)
		(property "Footprint" "antmicro-footprints:C_0402_1005Metric_EIA"
			(at 289.56 218.44 0)
			(effects
				(font
					(size 1.27 1.27)
					(thickness 0.15)
				)
				(justify left bottom)
				(hide yes)
			)
		)
		(property "Datasheet" "https://www.murata.com/products/productdetail?partno=GRM155R61H104KE14%23"
			(at 292.1 218.44 0)
			(effects
				(font
					(size 1.27 1.27)
					(thickness 0.15)
				)
				(justify left bottom)
				(hide yes)
			)
		)
		(property "Description" ""
			(at 276.86 238.76 0)
			(effects
				(font
					(size 1.27 1.27)
				)
				(hide yes)
			)
		)
		(property "MPN" "GRM155R61H104KE14D"
			(at 294.64 218.44 0)
			(effects
				(font
					(size 1.27 1.27)
					(thickness 0.15)
				)
				(justify left bottom)
				(hide yes)
			)
		)
		(property "Manufacturer" "Murata"
			(at 297.18 218.44 0)
			(effects
				(font
					(size 1.27 1.27)
					(thickness 0.15)
				)
				(justify left bottom)
				(hide yes)
			)
		)
		(property "License" "Apache-2.0"
			(at 299.72 218.44 0)
			(effects
				(font
					(size 1.27 1.27)
					(thickness 0.15)
				)
				(justify left bottom)
				(hide yes)
			)
		)
		(property "Author" "Antmicro"
			(at 302.26 218.44 0)
			(effects
				(font
					(size 1.27 1.27)
					(thickness 0.15)
				)
				(justify left bottom)
				(hide yes)
			)
		)
		(property "Val" "100n"
			(at 277.495 238.125 90)
			(effects
				(font
					(size 1.27 1.27)
					(thickness 0.15)
				)
				(justify right)
			)
		)
		(property "Voltage" "50V"
			(at 304.8 218.44 0)
			(effects
				(font
					(size 1.27 1.27)
				)
				(justify left bottom)
				(hide yes)
			)
		)
		(property "Dielectric" "X5R"
			(at 307.34 218.44 0)
			(effects
				(font
					(size 1.27 1.27)
				)
				(justify left bottom)
				(hide yes)
			)
		)
		(pin "1"
		)
		(pin "2"
		)
		(instances
			(project "data-center-rdimm-ddr5-tester"
				(path ""
					(reference "C91")
					(unit 1)
				)
			)
		)
	)
	(symbol
		(lib_id "antmicroCapacitors0402:C_1u_25V_0402")
		(at 102.87 147.32 90)
		(unit 1)
		(exclude_from_sim no)
		(in_bom yes)
		(on_board yes)
		(dnp no)
		(fields_autoplaced yes)
		(property "Reference" "C46"
			(at 105.41 143.5036 90)
			(effects
				(font
					(size 1.27 1.27)
					(thickness 0.15)
				)
				(justify right)
			)
		)
		(property "Value" "C_1u_25V_0402"
			(at 113.03 127 0)
			(effects
				(font
					(size 1.27 1.27)
					(thickness 0.15)
				)
				(justify left bottom)
				(hide yes)
			)
		)
		(property "Footprint" "antmicro-footprints:C_0402_1005Metric_EIA"
			(at 115.57 127 0)
			(effects
				(font
					(size 1.27 1.27)
					(thickness 0.15)
				)
				(justify left bottom)
				(hide yes)
			)
		)
		(property "Datasheet" "https://www.murata.com/products/productdetail?partno=GRM155R61E105KE11%23"
			(at 118.11 127 0)
			(effects
				(font
					(size 1.27 1.27)
					(thickness 0.15)
				)
				(justify left bottom)
				(hide yes)
			)
		)
		(property "Description" ""
			(at 102.87 147.32 0)
			(effects
				(font
					(size 1.27 1.27)
				)
				(hide yes)
			)
		)
		(property "MPN" "GRM155R61E105KE11J"
			(at 120.65 127 0)
			(effects
				(font
					(size 1.27 1.27)
					(thickness 0.15)
				)
				(justify left bottom)
				(hide yes)
			)
		)
		(property "Manufacturer" "Murata"
			(at 123.19 127 0)
			(effects
				(font
					(size 1.27 1.27)
					(thickness 0.15)
				)
				(justify left bottom)
				(hide yes)
			)
		)
		(property "License" "Apache-2.0"
			(at 125.73 127 0)
			(effects
				(font
					(size 1.27 1.27)
					(thickness 0.15)
				)
				(justify left bottom)
				(hide yes)
			)
		)
		(property "Author" "Antmicro"
			(at 128.27 127 0)
			(effects
				(font
					(size 1.27 1.27)
					(thickness 0.15)
				)
				(justify left bottom)
				(hide yes)
			)
		)
		(property "Val" "1u"
			(at 105.41 146.0436 90)
			(effects
				(font
					(size 1.27 1.27)
					(thickness 0.15)
				)
				(justify right)
			)
		)
		(property "Voltage" "25V"
			(at 130.81 127 0)
			(effects
				(font
					(size 1.27 1.27)
				)
				(justify left bottom)
				(hide yes)
			)
		)
		(property "Dielectric" "X5R"
			(at 133.35 127 0)
			(effects
				(font
					(size 1.27 1.27)
				)
				(justify left bottom)
				(hide yes)
			)
		)
		(pin "1"
		)
		(pin "2"
		)
		(instances
			(project "data-center-rdimm-ddr5-tester"
				(path ""
					(reference "C46")
					(unit 1)
				)
			)
		)
	)
	(symbol
		(lib_id "antmicropower:GND")
		(at 111.76 173.99 0)
		(unit 1)
		(exclude_from_sim no)
		(in_bom yes)
		(on_board yes)
		(dnp no)
		(fields_autoplaced yes)
		(property "Reference" "#PWR0128"
			(at 111.76 180.34 0)
			(effects
				(font
					(size 1.27 1.27)
				)
				(hide yes)
			)
		)
		(property "Value" "GND"
			(at 109.855 178.435 0)
			(effects
				(font
					(size 1.27 1.27)
					(thickness 0.15)
				)
				(justify left bottom)
			)
		)
		(property "Footprint" ""
			(at 120.65 181.61 0)
			(effects
				(font
					(size 1.27 1.27)
					(thickness 0.15)
				)
				(justify left bottom)
				(hide yes)
			)
		)
		(property "Datasheet" ""
			(at 120.65 186.69 0)
			(effects
				(font
					(size 1.27 1.27)
					(thickness 0.15)
				)
				(justify left bottom)
				(hide yes)
			)
		)
		(property "Description" ""
			(at 111.76 173.99 0)
			(effects
				(font
					(size 1.27 1.27)
				)
				(hide yes)
			)
		)
		(property "Author" "Antmicro"
			(at 120.65 179.07 0)
			(effects
				(font
					(size 1.27 1.27)
					(thickness 0.15)
				)
				(justify left bottom)
				(hide yes)
			)
		)
		(property "License" "Apache-2.0"
			(at 120.65 181.61 0)
			(effects
				(font
					(size 1.27 1.27)
					(thickness 0.15)
				)
				(justify left bottom)
				(hide yes)
			)
		)
		(pin "1"
		)
		(instances
			(project "data-center-rdimm-ddr5-tester"
				(path ""
					(reference "#PWR0128")
					(unit 1)
				)
			)
		)
	)
	(symbol
		(lib_id "antmicroCapacitors0402:C_100n_0402")
		(at 246.38 270.51 90)
		(unit 1)
		(exclude_from_sim no)
		(in_bom yes)
		(on_board yes)
		(dnp no)
		(property "Reference" "C17"
			(at 250.825 266.065 90)
			(effects
				(font
					(size 1.27 1.27)
					(thickness 0.15)
				)
				(justify left)
			)
		)
		(property "Value" "C_100n_0402"
			(at 256.54 250.19 0)
			(effects
				(font
					(size 1.27 1.27)
					(thickness 0.15)
				)
				(justify left bottom)
				(hide yes)
			)
		)
		(property "Footprint" "antmicro-footprints:C_0402_1005Metric_EIA"
			(at 259.08 250.19 0)
			(effects
				(font
					(size 1.27 1.27)
					(thickness 0.15)
				)
				(justify left bottom)
				(hide yes)
			)
		)
		(property "Datasheet" "https://www.murata.com/products/productdetail?partno=GRM155R61H104KE14%23"
			(at 261.62 250.19 0)
			(effects
				(font
					(size 1.27 1.27)
					(thickness 0.15)
				)
				(justify left bottom)
				(hide yes)
			)
		)
		(property "Description" ""
			(at 246.38 270.51 0)
			(effects
				(font
					(size 1.27 1.27)
				)
				(hide yes)
			)
		)
		(property "MPN" "GRM155R61H104KE14D"
			(at 264.16 250.19 0)
			(effects
				(font
					(size 1.27 1.27)
					(thickness 0.15)
				)
				(justify left bottom)
				(hide yes)
			)
		)
		(property "Manufacturer" "Murata"
			(at 266.7 250.19 0)
			(effects
				(font
					(size 1.27 1.27)
					(thickness 0.15)
				)
				(justify left bottom)
				(hide yes)
			)
		)
		(property "License" "Apache-2.0"
			(at 269.24 250.19 0)
			(effects
				(font
					(size 1.27 1.27)
					(thickness 0.15)
				)
				(justify left bottom)
				(hide yes)
			)
		)
		(property "Author" "Antmicro"
			(at 271.78 250.19 0)
			(effects
				(font
					(size 1.27 1.27)
					(thickness 0.15)
				)
				(justify left bottom)
				(hide yes)
			)
		)
		(property "Val" "100n"
			(at 252.095 269.875 90)
			(effects
				(font
					(size 1.27 1.27)
					(thickness 0.15)
				)
				(justify left)
			)
		)
		(property "Voltage" "50V"
			(at 274.32 250.19 0)
			(effects
				(font
					(size 1.27 1.27)
				)
				(justify left bottom)
				(hide yes)
			)
		)
		(property "Dielectric" "X5R"
			(at 276.86 250.19 0)
			(effects
				(font
					(size 1.27 1.27)
				)
				(justify left bottom)
				(hide yes)
			)
		)
		(pin "1"
		)
		(pin "2"
		)
		(instances
			(project "data-center-rdimm-ddr5-tester"
				(path ""
					(reference "C17")
					(unit 1)
				)
			)
		)
	)
	(symbol
		(lib_id "antmicropower:GND")
		(at 95.25 198.12 0)
		(unit 1)
		(exclude_from_sim no)
		(in_bom yes)
		(on_board yes)
		(dnp no)
		(fields_autoplaced yes)
		(property "Reference" "#PWR0312"
			(at 95.25 204.47 0)
			(effects
				(font
					(size 1.27 1.27)
				)
				(hide yes)
			)
		)
		(property "Value" "GND"
			(at 93.345 202.565 0)
			(effects
				(font
					(size 1.27 1.27)
					(thickness 0.15)
				)
				(justify left bottom)
			)
		)
		(property "Footprint" ""
			(at 104.14 205.74 0)
			(effects
				(font
					(size 1.27 1.27)
					(thickness 0.15)
				)
				(justify left bottom)
				(hide yes)
			)
		)
		(property "Datasheet" ""
			(at 104.14 210.82 0)
			(effects
				(font
					(size 1.27 1.27)
					(thickness 0.15)
				)
				(justify left bottom)
				(hide yes)
			)
		)
		(property "Description" ""
			(at 95.25 198.12 0)
			(effects
				(font
					(size 1.27 1.27)
				)
				(hide yes)
			)
		)
		(property "Author" "Antmicro"
			(at 104.14 203.2 0)
			(effects
				(font
					(size 1.27 1.27)
					(thickness 0.15)
				)
				(justify left bottom)
				(hide yes)
			)
		)
		(property "License" "Apache-2.0"
			(at 104.14 205.74 0)
			(effects
				(font
					(size 1.27 1.27)
					(thickness 0.15)
				)
				(justify left bottom)
				(hide yes)
			)
		)
		(pin "1"
		)
		(instances
			(project "data-center-rdimm-ddr5-tester"
				(path ""
					(reference "#PWR0312")
					(unit 1)
				)
			)
		)
	)
	(symbol
		(lib_id "antmicroCapacitors0402:C_10u_10V_0402")
		(at 240.03 270.51 90)
		(unit 1)
		(exclude_from_sim no)
		(in_bom yes)
		(on_board yes)
		(dnp no)
		(property "Reference" "C16"
			(at 241.3 266.065 90)
			(effects
				(font
					(size 1.27 1.27)
					(thickness 0.15)
				)
				(justify right)
			)
		)
		(property "Value" "C_10u_10V_0402"
			(at 250.19 250.19 0)
			(effects
				(font
					(size 1.27 1.27)
					(thickness 0.15)
				)
				(justify left bottom)
				(hide yes)
			)
		)
		(property "Footprint" "antmicro-footprints:C_0402_1005Metric_EIA"
			(at 252.73 250.19 0)
			(effects
				(font
					(size 1.27 1.27)
					(thickness 0.15)
				)
				(justify left bottom)
				(hide yes)
			)
		)
		(property "Datasheet" "https://www.murata.com/products/productdetail?partno=GRM155R61A106ME11%23"
			(at 255.27 250.19 0)
			(effects
				(font
					(size 1.27 1.27)
					(thickness 0.15)
				)
				(justify left bottom)
				(hide yes)
			)
		)
		(property "Description" ""
			(at 240.03 270.51 0)
			(effects
				(font
					(size 1.27 1.27)
				)
				(hide yes)
			)
		)
		(property "MPN" "GRM155R61A106ME11D"
			(at 257.81 250.19 0)
			(effects
				(font
					(size 1.27 1.27)
					(thickness 0.15)
				)
				(justify left bottom)
				(hide yes)
			)
		)
		(property "Manufacturer" "Murata"
			(at 260.35 250.19 0)
			(effects
				(font
					(size 1.27 1.27)
					(thickness 0.15)
				)
				(justify left bottom)
				(hide yes)
			)
		)
		(property "License" "Apache-2.0"
			(at 262.89 250.19 0)
			(effects
				(font
					(size 1.27 1.27)
					(thickness 0.15)
				)
				(justify left bottom)
				(hide yes)
			)
		)
		(property "Author" "Antmicro"
			(at 265.43 250.19 0)
			(effects
				(font
					(size 1.27 1.27)
					(thickness 0.15)
				)
				(justify left bottom)
				(hide yes)
			)
		)
		(property "Val" "10u"
			(at 241.3 269.875 90)
			(effects
				(font
					(size 1.27 1.27)
					(thickness 0.15)
				)
				(justify right)
			)
		)
		(property "Voltage" "10V"
			(at 267.97 250.19 0)
			(effects
				(font
					(size 1.27 1.27)
				)
				(justify left bottom)
				(hide yes)
			)
		)
		(property "Dielectric" "X5R"
			(at 270.51 250.19 0)
			(effects
				(font
					(size 1.27 1.27)
				)
				(justify left bottom)
				(hide yes)
			)
		)
		(pin "1"
		)
		(pin "2"
		)
		(instances
			(project "data-center-rdimm-ddr5-tester"
				(path ""
					(reference "C16")
					(unit 1)
				)
			)
		)
	)
	(symbol
		(lib_id "antmicropower:GND")
		(at 167.64 271.78 0)
		(unit 1)
		(exclude_from_sim no)
		(in_bom yes)
		(on_board yes)
		(dnp no)
		(fields_autoplaced yes)
		(property "Reference" "#PWR065"
			(at 167.64 278.13 0)
			(effects
				(font
					(size 1.27 1.27)
				)
				(hide yes)
			)
		)
		(property "Value" "GND"
			(at 165.735 276.225 0)
			(effects
				(font
					(size 1.27 1.27)
					(thickness 0.15)
				)
				(justify left bottom)
			)
		)
		(property "Footprint" ""
			(at 176.53 279.4 0)
			(effects
				(font
					(size 1.27 1.27)
					(thickness 0.15)
				)
				(justify left bottom)
				(hide yes)
			)
		)
		(property "Datasheet" ""
			(at 176.53 284.48 0)
			(effects
				(font
					(size 1.27 1.27)
					(thickness 0.15)
				)
				(justify left bottom)
				(hide yes)
			)
		)
		(property "Description" ""
			(at 167.64 271.78 0)
			(effects
				(font
					(size 1.27 1.27)
				)
				(hide yes)
			)
		)
		(property "Author" "Antmicro"
			(at 176.53 276.86 0)
			(effects
				(font
					(size 1.27 1.27)
					(thickness 0.15)
				)
				(justify left bottom)
				(hide yes)
			)
		)
		(property "License" "Apache-2.0"
			(at 176.53 279.4 0)
			(effects
				(font
					(size 1.27 1.27)
					(thickness 0.15)
				)
				(justify left bottom)
				(hide yes)
			)
		)
		(pin "1"
		)
		(instances
			(project "data-center-rdimm-ddr5-tester"
				(path ""
					(reference "#PWR065")
					(unit 1)
				)
			)
		)
	)
	(symbol
		(lib_id "antmicropower:GND")
		(at 171.45 241.3 0)
		(unit 1)
		(exclude_from_sim no)
		(in_bom yes)
		(on_board yes)
		(dnp no)
		(fields_autoplaced yes)
		(property "Reference" "#PWR067"
			(at 171.45 247.65 0)
			(effects
				(font
					(size 1.27 1.27)
				)
				(hide yes)
			)
		)
		(property "Value" "GND"
			(at 169.545 245.745 0)
			(effects
				(font
					(size 1.27 1.27)
					(thickness 0.15)
				)
				(justify left bottom)
			)
		)
		(property "Footprint" ""
			(at 180.34 248.92 0)
			(effects
				(font
					(size 1.27 1.27)
					(thickness 0.15)
				)
				(justify left bottom)
				(hide yes)
			)
		)
		(property "Datasheet" ""
			(at 180.34 254 0)
			(effects
				(font
					(size 1.27 1.27)
					(thickness 0.15)
				)
				(justify left bottom)
				(hide yes)
			)
		)
		(property "Description" ""
			(at 171.45 241.3 0)
			(effects
				(font
					(size 1.27 1.27)
				)
				(hide yes)
			)
		)
		(property "Author" "Antmicro"
			(at 180.34 246.38 0)
			(effects
				(font
					(size 1.27 1.27)
					(thickness 0.15)
				)
				(justify left bottom)
				(hide yes)
			)
		)
		(property "License" "Apache-2.0"
			(at 180.34 248.92 0)
			(effects
				(font
					(size 1.27 1.27)
					(thickness 0.15)
				)
				(justify left bottom)
				(hide yes)
			)
		)
		(pin "1"
		)
		(instances
			(project "data-center-rdimm-ddr5-tester"
				(path ""
					(reference "#PWR067")
					(unit 1)
				)
			)
		)
	)
	(symbol
		(lib_id "antmicropower:GND")
		(at 99.06 67.31 0)
		(mirror y)
		(unit 1)
		(exclude_from_sim no)
		(in_bom yes)
		(on_board yes)
		(dnp no)
		(fields_autoplaced yes)
		(property "Reference" "#PWR0101"
			(at 99.06 73.66 0)
			(effects
				(font
					(size 1.27 1.27)
				)
				(hide yes)
			)
		)
		(property "Value" "GND"
			(at 100.965 71.755 0)
			(effects
				(font
					(size 1.27 1.27)
					(thickness 0.15)
				)
				(justify left bottom)
			)
		)
		(property "Footprint" ""
			(at 90.17 74.93 0)
			(effects
				(font
					(size 1.27 1.27)
					(thickness 0.15)
				)
				(justify left bottom)
				(hide yes)
			)
		)
		(property "Datasheet" ""
			(at 90.17 80.01 0)
			(effects
				(font
					(size 1.27 1.27)
					(thickness 0.15)
				)
				(justify left bottom)
				(hide yes)
			)
		)
		(property "Description" ""
			(at 99.06 67.31 0)
			(effects
				(font
					(size 1.27 1.27)
				)
				(hide yes)
			)
		)
		(property "Author" "Antmicro"
			(at 90.17 72.39 0)
			(effects
				(font
					(size 1.27 1.27)
					(thickness 0.15)
				)
				(justify left bottom)
				(hide yes)
			)
		)
		(property "License" "Apache-2.0"
			(at 90.17 74.93 0)
			(effects
				(font
					(size 1.27 1.27)
					(thickness 0.15)
				)
				(justify left bottom)
				(hide yes)
			)
		)
		(pin "1"
		)
		(instances
			(project "data-center-rdimm-ddr5-tester"
				(path ""
					(reference "#PWR0101")
					(unit 1)
				)
			)
		)
	)
	(symbol
		(lib_id "antmicropower:GND")
		(at 340.36 101.6 0)
		(unit 1)
		(exclude_from_sim no)
		(in_bom yes)
		(on_board yes)
		(dnp no)
		(fields_autoplaced yes)
		(property "Reference" "#PWR0129"
			(at 340.36 107.95 0)
			(effects
				(font
					(size 1.27 1.27)
				)
				(hide yes)
			)
		)
		(property "Value" "GND"
			(at 338.455 106.045 0)
			(effects
				(font
					(size 1.27 1.27)
					(thickness 0.15)
				)
				(justify left bottom)
			)
		)
		(property "Footprint" ""
			(at 349.25 109.22 0)
			(effects
				(font
					(size 1.27 1.27)
					(thickness 0.15)
				)
				(justify left bottom)
				(hide yes)
			)
		)
		(property "Datasheet" ""
			(at 349.25 114.3 0)
			(effects
				(font
					(size 1.27 1.27)
					(thickness 0.15)
				)
				(justify left bottom)
				(hide yes)
			)
		)
		(property "Description" ""
			(at 340.36 101.6 0)
			(effects
				(font
					(size 1.27 1.27)
				)
				(hide yes)
			)
		)
		(property "Author" "Antmicro"
			(at 349.25 106.68 0)
			(effects
				(font
					(size 1.27 1.27)
					(thickness 0.15)
				)
				(justify left bottom)
				(hide yes)
			)
		)
		(property "License" "Apache-2.0"
			(at 349.25 109.22 0)
			(effects
				(font
					(size 1.27 1.27)
					(thickness 0.15)
				)
				(justify left bottom)
				(hide yes)
			)
		)
		(pin "1"
		)
		(instances
			(project "data-center-rdimm-ddr5-tester"
				(path ""
					(reference "#PWR0129")
					(unit 1)
				)
			)
		)
	)
	(symbol
		(lib_id "antmicroCapacitors0402:C_100n_0402")
		(at 78.74 119.38 90)
		(unit 1)
		(exclude_from_sim no)
		(in_bom yes)
		(on_board yes)
		(dnp no)
		(property "Reference" "C48"
			(at 79.375 114.935 90)
			(effects
				(font
					(size 1.27 1.27)
					(thickness 0.15)
				)
				(justify right)
			)
		)
		(property "Value" "C_100n_0402"
			(at 88.9 99.06 0)
			(effects
				(font
					(size 1.27 1.27)
					(thickness 0.15)
				)
				(justify left bottom)
				(hide yes)
			)
		)
		(property "Footprint" "antmicro-footprints:C_0402_1005Metric_EIA"
			(at 91.44 99.06 0)
			(effects
				(font
					(size 1.27 1.27)
					(thickness 0.15)
				)
				(justify left bottom)
				(hide yes)
			)
		)
		(property "Datasheet" "https://www.murata.com/products/productdetail?partno=GRM155R61H104KE14%23"
			(at 93.98 99.06 0)
			(effects
				(font
					(size 1.27 1.27)
					(thickness 0.15)
				)
				(justify left bottom)
				(hide yes)
			)
		)
		(property "Description" ""
			(at 78.74 119.38 0)
			(effects
				(font
					(size 1.27 1.27)
				)
				(hide yes)
			)
		)
		(property "MPN" "GRM155R61H104KE14D"
			(at 96.52 99.06 0)
			(effects
				(font
					(size 1.27 1.27)
					(thickness 0.15)
				)
				(justify left bottom)
				(hide yes)
			)
		)
		(property "Manufacturer" "Murata"
			(at 99.06 99.06 0)
			(effects
				(font
					(size 1.27 1.27)
					(thickness 0.15)
				)
				(justify left bottom)
				(hide yes)
			)
		)
		(property "License" "Apache-2.0"
			(at 101.6 99.06 0)
			(effects
				(font
					(size 1.27 1.27)
					(thickness 0.15)
				)
				(justify left bottom)
				(hide yes)
			)
		)
		(property "Author" "Antmicro"
			(at 104.14 99.06 0)
			(effects
				(font
					(size 1.27 1.27)
					(thickness 0.15)
				)
				(justify left bottom)
				(hide yes)
			)
		)
		(property "Val" "100n"
			(at 79.375 118.745 90)
			(effects
				(font
					(size 1.27 1.27)
					(thickness 0.15)
				)
				(justify right)
			)
		)
		(property "Voltage" "50V"
			(at 106.68 99.06 0)
			(effects
				(font
					(size 1.27 1.27)
				)
				(justify left bottom)
				(hide yes)
			)
		)
		(property "Dielectric" "X5R"
			(at 109.22 99.06 0)
			(effects
				(font
					(size 1.27 1.27)
				)
				(justify left bottom)
				(hide yes)
			)
		)
		(pin "1"
		)
		(pin "2"
		)
		(instances
			(project "data-center-rdimm-ddr5-tester"
				(path ""
					(reference "C48")
					(unit 1)
				)
			)
		)
	)
	(symbol
		(lib_id "antmicroCapacitors0402:C_100n_0402")
		(at 346.71 64.77 90)
		(unit 1)
		(exclude_from_sim no)
		(in_bom yes)
		(on_board yes)
		(dnp no)
		(property "Reference" "C104"
			(at 347.345 60.325 90)
			(effects
				(font
					(size 1.27 1.27)
					(thickness 0.15)
				)
				(justify right)
			)
		)
		(property "Value" "C_100n_0402"
			(at 356.87 44.45 0)
			(effects
				(font
					(size 1.27 1.27)
					(thickness 0.15)
				)
				(justify left bottom)
				(hide yes)
			)
		)
		(property "Footprint" "antmicro-footprints:C_0402_1005Metric_EIA"
			(at 359.41 44.45 0)
			(effects
				(font
					(size 1.27 1.27)
					(thickness 0.15)
				)
				(justify left bottom)
				(hide yes)
			)
		)
		(property "Datasheet" "https://www.murata.com/products/productdetail?partno=GRM155R61H104KE14%23"
			(at 361.95 44.45 0)
			(effects
				(font
					(size 1.27 1.27)
					(thickness 0.15)
				)
				(justify left bottom)
				(hide yes)
			)
		)
		(property "Description" ""
			(at 346.71 64.77 0)
			(effects
				(font
					(size 1.27 1.27)
				)
				(hide yes)
			)
		)
		(property "MPN" "GRM155R61H104KE14D"
			(at 364.49 44.45 0)
			(effects
				(font
					(size 1.27 1.27)
					(thickness 0.15)
				)
				(justify left bottom)
				(hide yes)
			)
		)
		(property "Manufacturer" "Murata"
			(at 367.03 44.45 0)
			(effects
				(font
					(size 1.27 1.27)
					(thickness 0.15)
				)
				(justify left bottom)
				(hide yes)
			)
		)
		(property "License" "Apache-2.0"
			(at 369.57 44.45 0)
			(effects
				(font
					(size 1.27 1.27)
					(thickness 0.15)
				)
				(justify left bottom)
				(hide yes)
			)
		)
		(property "Author" "Antmicro"
			(at 372.11 44.45 0)
			(effects
				(font
					(size 1.27 1.27)
					(thickness 0.15)
				)
				(justify left bottom)
				(hide yes)
			)
		)
		(property "Val" "100n"
			(at 347.345 64.135 90)
			(effects
				(font
					(size 1.27 1.27)
					(thickness 0.15)
				)
				(justify right)
			)
		)
		(property "Voltage" "50V"
			(at 374.65 44.45 0)
			(effects
				(font
					(size 1.27 1.27)
				)
				(justify left bottom)
				(hide yes)
			)
		)
		(property "Dielectric" "X5R"
			(at 377.19 44.45 0)
			(effects
				(font
					(size 1.27 1.27)
				)
				(justify left bottom)
				(hide yes)
			)
		)
		(pin "1"
		)
		(pin "2"
		)
		(instances
			(project "data-center-rdimm-ddr5-tester"
				(path ""
					(reference "C104")
					(unit 1)
				)
			)
		)
	)
	(symbol
		(lib_id "antmicroCapacitors0402:C_1u_25V_0402")
		(at 53.34 172.72 90)
		(unit 1)
		(exclude_from_sim no)
		(in_bom yes)
		(on_board yes)
		(dnp no)
		(fields_autoplaced yes)
		(property "Reference" "C52"
			(at 55.88 168.9036 90)
			(effects
				(font
					(size 1.27 1.27)
					(thickness 0.15)
				)
				(justify right)
			)
		)
		(property "Value" "C_1u_25V_0402"
			(at 63.5 152.4 0)
			(effects
				(font
					(size 1.27 1.27)
					(thickness 0.15)
				)
				(justify left bottom)
				(hide yes)
			)
		)
		(property "Footprint" "antmicro-footprints:C_0402_1005Metric_EIA"
			(at 66.04 152.4 0)
			(effects
				(font
					(size 1.27 1.27)
					(thickness 0.15)
				)
				(justify left bottom)
				(hide yes)
			)
		)
		(property "Datasheet" "https://www.murata.com/products/productdetail?partno=GRM155R61E105KE11%23"
			(at 68.58 152.4 0)
			(effects
				(font
					(size 1.27 1.27)
					(thickness 0.15)
				)
				(justify left bottom)
				(hide yes)
			)
		)
		(property "Description" ""
			(at 53.34 172.72 0)
			(effects
				(font
					(size 1.27 1.27)
				)
				(hide yes)
			)
		)
		(property "MPN" "GRM155R61E105KE11J"
			(at 71.12 152.4 0)
			(effects
				(font
					(size 1.27 1.27)
					(thickness 0.15)
				)
				(justify left bottom)
				(hide yes)
			)
		)
		(property "Manufacturer" "Murata"
			(at 73.66 152.4 0)
			(effects
				(font
					(size 1.27 1.27)
					(thickness 0.15)
				)
				(justify left bottom)
				(hide yes)
			)
		)
		(property "License" "Apache-2.0"
			(at 76.2 152.4 0)
			(effects
				(font
					(size 1.27 1.27)
					(thickness 0.15)
				)
				(justify left bottom)
				(hide yes)
			)
		)
		(property "Author" "Antmicro"
			(at 78.74 152.4 0)
			(effects
				(font
					(size 1.27 1.27)
					(thickness 0.15)
				)
				(justify left bottom)
				(hide yes)
			)
		)
		(property "Val" "1u"
			(at 55.88 171.4436 90)
			(effects
				(font
					(size 1.27 1.27)
					(thickness 0.15)
				)
				(justify right)
			)
		)
		(property "Voltage" "25V"
			(at 81.28 152.4 0)
			(effects
				(font
					(size 1.27 1.27)
				)
				(justify left bottom)
				(hide yes)
			)
		)
		(property "Dielectric" "X5R"
			(at 83.82 152.4 0)
			(effects
				(font
					(size 1.27 1.27)
				)
				(justify left bottom)
				(hide yes)
			)
		)
		(pin "1"
		)
		(pin "2"
		)
		(instances
			(project "data-center-rdimm-ddr5-tester"
				(path ""
					(reference "C52")
					(unit 1)
				)
			)
		)
	)
	(symbol
		(lib_id "antmicropower:GND")
		(at 365.76 134.62 0)
		(unit 1)
		(exclude_from_sim no)
		(in_bom yes)
		(on_board yes)
		(dnp no)
		(fields_autoplaced yes)
		(property "Reference" "#PWR0156"
			(at 365.76 140.97 0)
			(effects
				(font
					(size 1.27 1.27)
				)
				(hide yes)
			)
		)
		(property "Value" "GND"
			(at 363.855 139.065 0)
			(effects
				(font
					(size 1.27 1.27)
					(thickness 0.15)
				)
				(justify left bottom)
			)
		)
		(property "Footprint" ""
			(at 374.65 142.24 0)
			(effects
				(font
					(size 1.27 1.27)
					(thickness 0.15)
				)
				(justify left bottom)
				(hide yes)
			)
		)
		(property "Datasheet" ""
			(at 374.65 147.32 0)
			(effects
				(font
					(size 1.27 1.27)
					(thickness 0.15)
				)
				(justify left bottom)
				(hide yes)
			)
		)
		(property "Description" ""
			(at 365.76 134.62 0)
			(effects
				(font
					(size 1.27 1.27)
				)
				(hide yes)
			)
		)
		(property "Author" "Antmicro"
			(at 374.65 139.7 0)
			(effects
				(font
					(size 1.27 1.27)
					(thickness 0.15)
				)
				(justify left bottom)
				(hide yes)
			)
		)
		(property "License" "Apache-2.0"
			(at 374.65 142.24 0)
			(effects
				(font
					(size 1.27 1.27)
					(thickness 0.15)
				)
				(justify left bottom)
				(hide yes)
			)
		)
		(pin "1"
		)
		(instances
			(project "data-center-rdimm-ddr5-tester"
				(path ""
					(reference "#PWR0156")
					(unit 1)
				)
			)
		)
	)
	(symbol
		(lib_id "antmicroCapacitors0402:C_1u_25V_0402")
		(at 78.74 147.32 90)
		(unit 1)
		(exclude_from_sim no)
		(in_bom yes)
		(on_board yes)
		(dnp no)
		(fields_autoplaced yes)
		(property "Reference" "C41"
			(at 81.28 143.5036 90)
			(effects
				(font
					(size 1.27 1.27)
					(thickness 0.15)
				)
				(justify right)
			)
		)
		(property "Value" "C_1u_25V_0402"
			(at 88.9 127 0)
			(effects
				(font
					(size 1.27 1.27)
					(thickness 0.15)
				)
				(justify left bottom)
				(hide yes)
			)
		)
		(property "Footprint" "antmicro-footprints:C_0402_1005Metric_EIA"
			(at 91.44 127 0)
			(effects
				(font
					(size 1.27 1.27)
					(thickness 0.15)
				)
				(justify left bottom)
				(hide yes)
			)
		)
		(property "Datasheet" "https://www.murata.com/products/productdetail?partno=GRM155R61E105KE11%23"
			(at 93.98 127 0)
			(effects
				(font
					(size 1.27 1.27)
					(thickness 0.15)
				)
				(justify left bottom)
				(hide yes)
			)
		)
		(property "Description" ""
			(at 78.74 147.32 0)
			(effects
				(font
					(size 1.27 1.27)
				)
				(hide yes)
			)
		)
		(property "MPN" "GRM155R61E105KE11J"
			(at 96.52 127 0)
			(effects
				(font
					(size 1.27 1.27)
					(thickness 0.15)
				)
				(justify left bottom)
				(hide yes)
			)
		)
		(property "Manufacturer" "Murata"
			(at 99.06 127 0)
			(effects
				(font
					(size 1.27 1.27)
					(thickness 0.15)
				)
				(justify left bottom)
				(hide yes)
			)
		)
		(property "License" "Apache-2.0"
			(at 101.6 127 0)
			(effects
				(font
					(size 1.27 1.27)
					(thickness 0.15)
				)
				(justify left bottom)
				(hide yes)
			)
		)
		(property "Author" "Antmicro"
			(at 104.14 127 0)
			(effects
				(font
					(size 1.27 1.27)
					(thickness 0.15)
				)
				(justify left bottom)
				(hide yes)
			)
		)
		(property "Val" "1u"
			(at 81.28 146.0436 90)
			(effects
				(font
					(size 1.27 1.27)
					(thickness 0.15)
				)
				(justify right)
			)
		)
		(property "Voltage" "25V"
			(at 106.68 127 0)
			(effects
				(font
					(size 1.27 1.27)
				)
				(justify left bottom)
				(hide yes)
			)
		)
		(property "Dielectric" "X5R"
			(at 109.22 127 0)
			(effects
				(font
					(size 1.27 1.27)
				)
				(justify left bottom)
				(hide yes)
			)
		)
		(pin "1"
		)
		(pin "2"
		)
		(instances
			(project "data-center-rdimm-ddr5-tester"
				(path ""
					(reference "C41")
					(unit 1)
				)
			)
		)
	)
	(symbol
		(lib_id "antmicroCapacitors0402:C_100n_0402")
		(at 232.41 240.03 90)
		(unit 1)
		(exclude_from_sim no)
		(in_bom yes)
		(on_board yes)
		(dnp no)
		(property "Reference" "C74"
			(at 236.855 235.585 90)
			(effects
				(font
					(size 1.27 1.27)
					(thickness 0.15)
				)
				(justify left)
			)
		)
		(property "Value" "C_100n_0402"
			(at 242.57 219.71 0)
			(effects
				(font
					(size 1.27 1.27)
					(thickness 0.15)
				)
				(justify left bottom)
				(hide yes)
			)
		)
		(property "Footprint" "antmicro-footprints:C_0402_1005Metric_EIA"
			(at 245.11 219.71 0)
			(effects
				(font
					(size 1.27 1.27)
					(thickness 0.15)
				)
				(justify left bottom)
				(hide yes)
			)
		)
		(property "Datasheet" "https://www.murata.com/products/productdetail?partno=GRM155R61H104KE14%23"
			(at 247.65 219.71 0)
			(effects
				(font
					(size 1.27 1.27)
					(thickness 0.15)
				)
				(justify left bottom)
				(hide yes)
			)
		)
		(property "Description" ""
			(at 232.41 240.03 0)
			(effects
				(font
					(size 1.27 1.27)
				)
				(hide yes)
			)
		)
		(property "MPN" "GRM155R61H104KE14D"
			(at 250.19 219.71 0)
			(effects
				(font
					(size 1.27 1.27)
					(thickness 0.15)
				)
				(justify left bottom)
				(hide yes)
			)
		)
		(property "Manufacturer" "Murata"
			(at 252.73 219.71 0)
			(effects
				(font
					(size 1.27 1.27)
					(thickness 0.15)
				)
				(justify left bottom)
				(hide yes)
			)
		)
		(property "License" "Apache-2.0"
			(at 255.27 219.71 0)
			(effects
				(font
					(size 1.27 1.27)
					(thickness 0.15)
				)
				(justify left bottom)
				(hide yes)
			)
		)
		(property "Author" "Antmicro"
			(at 257.81 219.71 0)
			(effects
				(font
					(size 1.27 1.27)
					(thickness 0.15)
				)
				(justify left bottom)
				(hide yes)
			)
		)
		(property "Val" "100n"
			(at 238.125 239.395 90)
			(effects
				(font
					(size 1.27 1.27)
					(thickness 0.15)
				)
				(justify left)
			)
		)
		(property "Voltage" "50V"
			(at 260.35 219.71 0)
			(effects
				(font
					(size 1.27 1.27)
				)
				(justify left bottom)
				(hide yes)
			)
		)
		(property "Dielectric" "X5R"
			(at 262.89 219.71 0)
			(effects
				(font
					(size 1.27 1.27)
				)
				(justify left bottom)
				(hide yes)
			)
		)
		(pin "1"
		)
		(pin "2"
		)
		(instances
			(project "data-center-rdimm-ddr5-tester"
				(path ""
					(reference "C74")
					(unit 1)
				)
			)
		)
	)
	(symbol
		(lib_id "antmicropower:GND")
		(at 80.01 67.31 0)
		(mirror y)
		(unit 1)
		(exclude_from_sim no)
		(in_bom yes)
		(on_board yes)
		(dnp no)
		(fields_autoplaced yes)
		(property "Reference" "#PWR043"
			(at 80.01 73.66 0)
			(effects
				(font
					(size 1.27 1.27)
				)
				(hide yes)
			)
		)
		(property "Value" "GND"
			(at 81.915 71.755 0)
			(effects
				(font
					(size 1.27 1.27)
					(thickness 0.15)
				)
				(justify left bottom)
			)
		)
		(property "Footprint" ""
			(at 71.12 74.93 0)
			(effects
				(font
					(size 1.27 1.27)
					(thickness 0.15)
				)
				(justify left bottom)
				(hide yes)
			)
		)
		(property "Datasheet" ""
			(at 71.12 80.01 0)
			(effects
				(font
					(size 1.27 1.27)
					(thickness 0.15)
				)
				(justify left bottom)
				(hide yes)
			)
		)
		(property "Description" ""
			(at 80.01 67.31 0)
			(effects
				(font
					(size 1.27 1.27)
				)
				(hide yes)
			)
		)
		(property "Author" "Antmicro"
			(at 71.12 72.39 0)
			(effects
				(font
					(size 1.27 1.27)
					(thickness 0.15)
				)
				(justify left bottom)
				(hide yes)
			)
		)
		(property "License" "Apache-2.0"
			(at 71.12 74.93 0)
			(effects
				(font
					(size 1.27 1.27)
					(thickness 0.15)
				)
				(justify left bottom)
				(hide yes)
			)
		)
		(pin "1"
		)
		(instances
			(project "data-center-rdimm-ddr5-tester"
				(path ""
					(reference "#PWR043")
					(unit 1)
				)
			)
		)
	)
	(symbol
		(lib_id "antmicropower:GND")
		(at 104.14 120.65 0)
		(unit 1)
		(exclude_from_sim no)
		(in_bom yes)
		(on_board yes)
		(dnp no)
		(fields_autoplaced yes)
		(property "Reference" "#PWR0113"
			(at 104.14 127 0)
			(effects
				(font
					(size 1.27 1.27)
				)
				(hide yes)
			)
		)
		(property "Value" "GND"
			(at 102.235 125.095 0)
			(effects
				(font
					(size 1.27 1.27)
					(thickness 0.15)
				)
				(justify left bottom)
			)
		)
		(property "Footprint" ""
			(at 113.03 128.27 0)
			(effects
				(font
					(size 1.27 1.27)
					(thickness 0.15)
				)
				(justify left bottom)
				(hide yes)
			)
		)
		(property "Datasheet" ""
			(at 113.03 133.35 0)
			(effects
				(font
					(size 1.27 1.27)
					(thickness 0.15)
				)
				(justify left bottom)
				(hide yes)
			)
		)
		(property "Description" ""
			(at 104.14 120.65 0)
			(effects
				(font
					(size 1.27 1.27)
				)
				(hide yes)
			)
		)
		(property "Author" "Antmicro"
			(at 113.03 125.73 0)
			(effects
				(font
					(size 1.27 1.27)
					(thickness 0.15)
				)
				(justify left bottom)
				(hide yes)
			)
		)
		(property "License" "Apache-2.0"
			(at 113.03 128.27 0)
			(effects
				(font
					(size 1.27 1.27)
					(thickness 0.15)
				)
				(justify left bottom)
				(hide yes)
			)
		)
		(pin "1"
		)
		(instances
			(project "data-center-rdimm-ddr5-tester"
				(path ""
					(reference "#PWR0113")
					(unit 1)
				)
			)
		)
	)
	(symbol
		(lib_id "antmicropower:GND")
		(at 111.76 198.12 0)
		(unit 1)
		(exclude_from_sim no)
		(in_bom yes)
		(on_board yes)
		(dnp no)
		(fields_autoplaced yes)
		(property "Reference" "#PWR0316"
			(at 111.76 204.47 0)
			(effects
				(font
					(size 1.27 1.27)
				)
				(hide yes)
			)
		)
		(property "Value" "GND"
			(at 109.855 202.565 0)
			(effects
				(font
					(size 1.27 1.27)
					(thickness 0.15)
				)
				(justify left bottom)
			)
		)
		(property "Footprint" ""
			(at 120.65 205.74 0)
			(effects
				(font
					(size 1.27 1.27)
					(thickness 0.15)
				)
				(justify left bottom)
				(hide yes)
			)
		)
		(property "Datasheet" ""
			(at 120.65 210.82 0)
			(effects
				(font
					(size 1.27 1.27)
					(thickness 0.15)
				)
				(justify left bottom)
				(hide yes)
			)
		)
		(property "Description" ""
			(at 111.76 198.12 0)
			(effects
				(font
					(size 1.27 1.27)
				)
				(hide yes)
			)
		)
		(property "Author" "Antmicro"
			(at 120.65 203.2 0)
			(effects
				(font
					(size 1.27 1.27)
					(thickness 0.15)
				)
				(justify left bottom)
				(hide yes)
			)
		)
		(property "License" "Apache-2.0"
			(at 120.65 205.74 0)
			(effects
				(font
					(size 1.27 1.27)
					(thickness 0.15)
				)
				(justify left bottom)
				(hide yes)
			)
		)
		(pin "1"
		)
		(instances
			(project "data-center-rdimm-ddr5-tester"
				(path ""
					(reference "#PWR0316")
					(unit 1)
				)
			)
		)
	)
	(symbol
		(lib_id "antmicroCapacitors0402:C_100n_0402")
		(at 365.76 133.35 90)
		(unit 1)
		(exclude_from_sim no)
		(in_bom yes)
		(on_board yes)
		(dnp no)
		(property "Reference" "C100"
			(at 366.395 128.905 90)
			(effects
				(font
					(size 1.27 1.27)
					(thickness 0.15)
				)
				(justify right)
			)
		)
		(property "Value" "C_100n_0402"
			(at 375.92 113.03 0)
			(effects
				(font
					(size 1.27 1.27)
					(thickness 0.15)
				)
				(justify left bottom)
				(hide yes)
			)
		)
		(property "Footprint" "antmicro-footprints:C_0402_1005Metric_EIA"
			(at 378.46 113.03 0)
			(effects
				(font
					(size 1.27 1.27)
					(thickness 0.15)
				)
				(justify left bottom)
				(hide yes)
			)
		)
		(property "Datasheet" "https://www.murata.com/products/productdetail?partno=GRM155R61H104KE14%23"
			(at 381 113.03 0)
			(effects
				(font
					(size 1.27 1.27)
					(thickness 0.15)
				)
				(justify left bottom)
				(hide yes)
			)
		)
		(property "Description" ""
			(at 365.76 133.35 0)
			(effects
				(font
					(size 1.27 1.27)
				)
				(hide yes)
			)
		)
		(property "MPN" "GRM155R61H104KE14D"
			(at 383.54 113.03 0)
			(effects
				(font
					(size 1.27 1.27)
					(thickness 0.15)
				)
				(justify left bottom)
				(hide yes)
			)
		)
		(property "Manufacturer" "Murata"
			(at 386.08 113.03 0)
			(effects
				(font
					(size 1.27 1.27)
					(thickness 0.15)
				)
				(justify left bottom)
				(hide yes)
			)
		)
		(property "License" "Apache-2.0"
			(at 388.62 113.03 0)
			(effects
				(font
					(size 1.27 1.27)
					(thickness 0.15)
				)
				(justify left bottom)
				(hide yes)
			)
		)
		(property "Author" "Antmicro"
			(at 391.16 113.03 0)
			(effects
				(font
					(size 1.27 1.27)
					(thickness 0.15)
				)
				(justify left bottom)
				(hide yes)
			)
		)
		(property "Val" "100n"
			(at 366.395 132.715 90)
			(effects
				(font
					(size 1.27 1.27)
					(thickness 0.15)
				)
				(justify right)
			)
		)
		(property "Voltage" "50V"
			(at 393.7 113.03 0)
			(effects
				(font
					(size 1.27 1.27)
				)
				(justify left bottom)
				(hide yes)
			)
		)
		(property "Dielectric" "X5R"
			(at 396.24 113.03 0)
			(effects
				(font
					(size 1.27 1.27)
				)
				(justify left bottom)
				(hide yes)
			)
		)
		(pin "1"
		)
		(pin "2"
		)
		(instances
			(project "data-center-rdimm-ddr5-tester"
				(path ""
					(reference "C100")
					(unit 1)
				)
			)
		)
	)
	(symbol
		(lib_id "antmicropower:GND")
		(at 262.89 241.3 0)
		(unit 1)
		(exclude_from_sim no)
		(in_bom yes)
		(on_board yes)
		(dnp no)
		(fields_autoplaced yes)
		(property "Reference" "#PWR0139"
			(at 262.89 247.65 0)
			(effects
				(font
					(size 1.27 1.27)
				)
				(hide yes)
			)
		)
		(property "Value" "GND"
			(at 260.985 245.745 0)
			(effects
				(font
					(size 1.27 1.27)
					(thickness 0.15)
				)
				(justify left bottom)
			)
		)
		(property "Footprint" ""
			(at 271.78 248.92 0)
			(effects
				(font
					(size 1.27 1.27)
					(thickness 0.15)
				)
				(justify left bottom)
				(hide yes)
			)
		)
		(property "Datasheet" ""
			(at 271.78 254 0)
			(effects
				(font
					(size 1.27 1.27)
					(thickness 0.15)
				)
				(justify left bottom)
				(hide yes)
			)
		)
		(property "Description" ""
			(at 262.89 241.3 0)
			(effects
				(font
					(size 1.27 1.27)
				)
				(hide yes)
			)
		)
		(property "Author" "Antmicro"
			(at 271.78 246.38 0)
			(effects
				(font
					(size 1.27 1.27)
					(thickness 0.15)
				)
				(justify left bottom)
				(hide yes)
			)
		)
		(property "License" "Apache-2.0"
			(at 271.78 248.92 0)
			(effects
				(font
					(size 1.27 1.27)
					(thickness 0.15)
				)
				(justify left bottom)
				(hide yes)
			)
		)
		(pin "1"
		)
		(instances
			(project "data-center-rdimm-ddr5-tester"
				(path ""
					(reference "#PWR0139")
					(unit 1)
				)
			)
		)
	)
	(symbol
		(lib_id "antmicroCapacitors0402:C_10u_10V_0402")
		(at 198.12 240.03 90)
		(unit 1)
		(exclude_from_sim no)
		(in_bom yes)
		(on_board yes)
		(dnp no)
		(property "Reference" "C49"
			(at 199.39 235.585 90)
			(effects
				(font
					(size 1.27 1.27)
					(thickness 0.15)
				)
				(justify right)
			)
		)
		(property "Value" "C_10u_10V_0402"
			(at 208.28 219.71 0)
			(effects
				(font
					(size 1.27 1.27)
					(thickness 0.15)
				)
				(justify left bottom)
				(hide yes)
			)
		)
		(property "Footprint" "antmicro-footprints:C_0402_1005Metric_EIA"
			(at 210.82 219.71 0)
			(effects
				(font
					(size 1.27 1.27)
					(thickness 0.15)
				)
				(justify left bottom)
				(hide yes)
			)
		)
		(property "Datasheet" "https://www.murata.com/products/productdetail?partno=GRM155R61A106ME11%23"
			(at 213.36 219.71 0)
			(effects
				(font
					(size 1.27 1.27)
					(thickness 0.15)
				)
				(justify left bottom)
				(hide yes)
			)
		)
		(property "Description" ""
			(at 198.12 240.03 0)
			(effects
				(font
					(size 1.27 1.27)
				)
				(hide yes)
			)
		)
		(property "MPN" "GRM155R61A106ME11D"
			(at 215.9 219.71 0)
			(effects
				(font
					(size 1.27 1.27)
					(thickness 0.15)
				)
				(justify left bottom)
				(hide yes)
			)
		)
		(property "Manufacturer" "Murata"
			(at 218.44 219.71 0)
			(effects
				(font
					(size 1.27 1.27)
					(thickness 0.15)
				)
				(justify left bottom)
				(hide yes)
			)
		)
		(property "License" "Apache-2.0"
			(at 220.98 219.71 0)
			(effects
				(font
					(size 1.27 1.27)
					(thickness 0.15)
				)
				(justify left bottom)
				(hide yes)
			)
		)
		(property "Author" "Antmicro"
			(at 223.52 219.71 0)
			(effects
				(font
					(size 1.27 1.27)
					(thickness 0.15)
				)
				(justify left bottom)
				(hide yes)
			)
		)
		(property "Val" "10u"
			(at 199.39 239.395 90)
			(effects
				(font
					(size 1.27 1.27)
					(thickness 0.15)
				)
				(justify right)
			)
		)
		(property "Voltage" "10V"
			(at 226.06 219.71 0)
			(effects
				(font
					(size 1.27 1.27)
				)
				(justify left bottom)
				(hide yes)
			)
		)
		(property "Dielectric" "X5R"
			(at 228.6 219.71 0)
			(effects
				(font
					(size 1.27 1.27)
				)
				(justify left bottom)
				(hide yes)
			)
		)
		(pin "1"
		)
		(pin "2"
		)
		(instances
			(project "data-center-rdimm-ddr5-tester"
				(path ""
					(reference "C49")
					(unit 1)
				)
			)
		)
	)
	(symbol
		(lib_id "antmicroCapacitors0603:C_47u_0603")
		(at 336.55 168.91 270)
		(unit 1)
		(exclude_from_sim no)
		(in_bom yes)
		(on_board yes)
		(dnp no)
		(property "Reference" "C31"
			(at 336.55 169.545 90)
			(effects
				(font
					(size 1.27 1.27)
				)
				(justify left)
			)
		)
		(property "Value" "C_47u_0603"
			(at 326.39 189.23 0)
			(effects
				(font
					(size 1.27 1.27)
					(thickness 0.15)
				)
				(justify left bottom)
				(hide yes)
			)
		)
		(property "Footprint" "antmicro-footprints:C_0603_1608Metric"
			(at 323.85 189.23 0)
			(effects
				(font
					(size 1.27 1.27)
					(thickness 0.15)
				)
				(justify left bottom)
				(hide yes)
			)
		)
		(property "Datasheet" "https://www.murata.com/products/productdetail?partno=GRM188R60J476ME15%23"
			(at 321.31 189.23 0)
			(effects
				(font
					(size 1.27 1.27)
					(thickness 0.15)
				)
				(justify left bottom)
				(hide yes)
			)
		)
		(property "Description" ""
			(at 336.55 168.91 0)
			(effects
				(font
					(size 1.27 1.27)
				)
				(hide yes)
			)
		)
		(property "Manufacturer" "Murata"
			(at 316.23 189.23 0)
			(effects
				(font
					(size 1.27 1.27)
					(thickness 0.15)
				)
				(justify left bottom)
				(hide yes)
			)
		)
		(property "MPN" "GRM188R60J476ME15D"
			(at 318.77 189.23 0)
			(effects
				(font
					(size 1.27 1.27)
					(thickness 0.15)
				)
				(justify left bottom)
				(hide yes)
			)
		)
		(property "Val" "47u"
			(at 336.55 173.355 90)
			(effects
				(font
					(size 1.27 1.27)
					(thickness 0.15)
				)
				(justify left)
			)
		)
		(property "License" "Apache-2.0"
			(at 313.69 189.23 0)
			(effects
				(font
					(size 1.27 1.27)
					(thickness 0.15)
				)
				(justify left bottom)
				(hide yes)
			)
		)
		(property "Author" "Antmicro"
			(at 311.15 189.23 0)
			(effects
				(font
					(size 1.27 1.27)
					(thickness 0.15)
				)
				(justify left bottom)
				(hide yes)
			)
		)
		(property "Voltage" ""
			(at 308.61 189.23 0)
			(effects
				(font
					(size 1.27 1.27)
				)
				(justify left bottom)
				(hide yes)
			)
		)
		(property "Dielectric" ""
			(at 306.07 189.23 0)
			(effects
				(font
					(size 1.27 1.27)
				)
				(justify left bottom)
				(hide yes)
			)
		)
		(pin "1"
		)
		(pin "2"
		)
		(instances
			(project "data-center-rdimm-ddr5-tester"
				(path ""
					(reference "C31")
					(unit 1)
				)
			)
		)
	)
	(symbol
		(lib_id "antmicropower:GND")
		(at 60.96 67.31 0)
		(mirror y)
		(unit 1)
		(exclude_from_sim no)
		(in_bom yes)
		(on_board yes)
		(dnp no)
		(fields_autoplaced yes)
		(property "Reference" "#PWR072"
			(at 60.96 73.66 0)
			(effects
				(font
					(size 1.27 1.27)
				)
				(hide yes)
			)
		)
		(property "Value" "GND"
			(at 62.865 71.755 0)
			(effects
				(font
					(size 1.27 1.27)
					(thickness 0.15)
				)
				(justify left bottom)
			)
		)
		(property "Footprint" ""
			(at 52.07 74.93 0)
			(effects
				(font
					(size 1.27 1.27)
					(thickness 0.15)
				)
				(justify left bottom)
				(hide yes)
			)
		)
		(property "Datasheet" ""
			(at 52.07 80.01 0)
			(effects
				(font
					(size 1.27 1.27)
					(thickness 0.15)
				)
				(justify left bottom)
				(hide yes)
			)
		)
		(property "Description" ""
			(at 60.96 67.31 0)
			(effects
				(font
					(size 1.27 1.27)
				)
				(hide yes)
			)
		)
		(property "Author" "Antmicro"
			(at 52.07 72.39 0)
			(effects
				(font
					(size 1.27 1.27)
					(thickness 0.15)
				)
				(justify left bottom)
				(hide yes)
			)
		)
		(property "License" "Apache-2.0"
			(at 52.07 74.93 0)
			(effects
				(font
					(size 1.27 1.27)
					(thickness 0.15)
				)
				(justify left bottom)
				(hide yes)
			)
		)
		(pin "1"
		)
		(instances
			(project "data-center-rdimm-ddr5-tester"
				(path ""
					(reference "#PWR072")
					(unit 1)
				)
			)
		)
	)
	(symbol
		(lib_id "antmicroCapacitors0402:C_10u_10V_0402")
		(at 34.29 240.03 90)
		(unit 1)
		(exclude_from_sim no)
		(in_bom yes)
		(on_board yes)
		(dnp no)
		(property "Reference" "C27"
			(at 35.56 235.585 90)
			(effects
				(font
					(size 1.27 1.27)
					(thickness 0.15)
				)
				(justify right)
			)
		)
		(property "Value" "C_10u_10V_0402"
			(at 44.45 219.71 0)
			(effects
				(font
					(size 1.27 1.27)
					(thickness 0.15)
				)
				(justify left bottom)
				(hide yes)
			)
		)
		(property "Footprint" "antmicro-footprints:C_0402_1005Metric_EIA"
			(at 46.99 219.71 0)
			(effects
				(font
					(size 1.27 1.27)
					(thickness 0.15)
				)
				(justify left bottom)
				(hide yes)
			)
		)
		(property "Datasheet" "https://www.murata.com/products/productdetail?partno=GRM155R61A106ME11%23"
			(at 49.53 219.71 0)
			(effects
				(font
					(size 1.27 1.27)
					(thickness 0.15)
				)
				(justify left bottom)
				(hide yes)
			)
		)
		(property "Description" ""
			(at 34.29 240.03 0)
			(effects
				(font
					(size 1.27 1.27)
				)
				(hide yes)
			)
		)
		(property "MPN" "GRM155R61A106ME11D"
			(at 52.07 219.71 0)
			(effects
				(font
					(size 1.27 1.27)
					(thickness 0.15)
				)
				(justify left bottom)
				(hide yes)
			)
		)
		(property "Manufacturer" "Murata"
			(at 54.61 219.71 0)
			(effects
				(font
					(size 1.27 1.27)
					(thickness 0.15)
				)
				(justify left bottom)
				(hide yes)
			)
		)
		(property "License" "Apache-2.0"
			(at 57.15 219.71 0)
			(effects
				(font
					(size 1.27 1.27)
					(thickness 0.15)
				)
				(justify left bottom)
				(hide yes)
			)
		)
		(property "Author" "Antmicro"
			(at 59.69 219.71 0)
			(effects
				(font
					(size 1.27 1.27)
					(thickness 0.15)
				)
				(justify left bottom)
				(hide yes)
			)
		)
		(property "Val" "10u"
			(at 35.56 239.395 90)
			(effects
				(font
					(size 1.27 1.27)
					(thickness 0.15)
				)
				(justify right)
			)
		)
		(property "Voltage" "10V"
			(at 62.23 219.71 0)
			(effects
				(font
					(size 1.27 1.27)
				)
				(justify left bottom)
				(hide yes)
			)
		)
		(property "Dielectric" "X5R"
			(at 64.77 219.71 0)
			(effects
				(font
					(size 1.27 1.27)
				)
				(justify left bottom)
				(hide yes)
			)
		)
		(pin "1"
		)
		(pin "2"
		)
		(instances
			(project "data-center-rdimm-ddr5-tester"
				(path ""
					(reference "C27")
					(unit 1)
				)
			)
		)
	)
	(symbol
		(lib_id "antmicropower:GND")
		(at 67.31 242.57 0)
		(unit 1)
		(exclude_from_sim no)
		(in_bom yes)
		(on_board yes)
		(dnp no)
		(fields_autoplaced yes)
		(property "Reference" "#PWR0130"
			(at 67.31 248.92 0)
			(effects
				(font
					(size 1.27 1.27)
				)
				(hide yes)
			)
		)
		(property "Value" "GND"
			(at 65.405 247.015 0)
			(effects
				(font
					(size 1.27 1.27)
					(thickness 0.15)
				)
				(justify left bottom)
			)
		)
		(property "Footprint" ""
			(at 76.2 250.19 0)
			(effects
				(font
					(size 1.27 1.27)
					(thickness 0.15)
				)
				(justify left bottom)
				(hide yes)
			)
		)
		(property "Datasheet" ""
			(at 76.2 255.27 0)
			(effects
				(font
					(size 1.27 1.27)
					(thickness 0.15)
				)
				(justify left bottom)
				(hide yes)
			)
		)
		(property "Description" ""
			(at 67.31 242.57 0)
			(effects
				(font
					(size 1.27 1.27)
				)
				(hide yes)
			)
		)
		(property "Author" "Antmicro"
			(at 76.2 247.65 0)
			(effects
				(font
					(size 1.27 1.27)
					(thickness 0.15)
				)
				(justify left bottom)
				(hide yes)
			)
		)
		(property "License" "Apache-2.0"
			(at 76.2 250.19 0)
			(effects
				(font
					(size 1.27 1.27)
					(thickness 0.15)
				)
				(justify left bottom)
				(hide yes)
			)
		)
		(pin "1"
		)
		(instances
			(project "data-center-rdimm-ddr5-tester"
				(path ""
					(reference "#PWR0130")
					(unit 1)
				)
			)
		)
	)
	(symbol
		(lib_id "antmicropower:GND")
		(at 44.45 173.99 0)
		(unit 1)
		(exclude_from_sim no)
		(in_bom yes)
		(on_board yes)
		(dnp no)
		(fields_autoplaced yes)
		(property "Reference" "#PWR098"
			(at 44.45 180.34 0)
			(effects
				(font
					(size 1.27 1.27)
				)
				(hide yes)
			)
		)
		(property "Value" "GND"
			(at 42.545 178.435 0)
			(effects
				(font
					(size 1.27 1.27)
					(thickness 0.15)
				)
				(justify left bottom)
			)
		)
		(property "Footprint" ""
			(at 53.34 181.61 0)
			(effects
				(font
					(size 1.27 1.27)
					(thickness 0.15)
				)
				(justify left bottom)
				(hide yes)
			)
		)
		(property "Datasheet" ""
			(at 53.34 186.69 0)
			(effects
				(font
					(size 1.27 1.27)
					(thickness 0.15)
				)
				(justify left bottom)
				(hide yes)
			)
		)
		(property "Description" ""
			(at 44.45 173.99 0)
			(effects
				(font
					(size 1.27 1.27)
				)
				(hide yes)
			)
		)
		(property "Author" "Antmicro"
			(at 53.34 179.07 0)
			(effects
				(font
					(size 1.27 1.27)
					(thickness 0.15)
				)
				(justify left bottom)
				(hide yes)
			)
		)
		(property "License" "Apache-2.0"
			(at 53.34 181.61 0)
			(effects
				(font
					(size 1.27 1.27)
					(thickness 0.15)
				)
				(justify left bottom)
				(hide yes)
			)
		)
		(pin "1"
		)
		(instances
			(project "data-center-rdimm-ddr5-tester"
				(path ""
					(reference "#PWR098")
					(unit 1)
				)
			)
		)
	)
	(symbol
		(lib_id "antmicropower:GND")
		(at 177.8 241.3 0)
		(unit 1)
		(exclude_from_sim no)
		(in_bom yes)
		(on_board yes)
		(dnp no)
		(fields_autoplaced yes)
		(property "Reference" "#PWR071"
			(at 177.8 247.65 0)
			(effects
				(font
					(size 1.27 1.27)
				)
				(hide yes)
			)
		)
		(property "Value" "GND"
			(at 175.895 245.745 0)
			(effects
				(font
					(size 1.27 1.27)
					(thickness 0.15)
				)
				(justify left bottom)
			)
		)
		(property "Footprint" ""
			(at 186.69 248.92 0)
			(effects
				(font
					(size 1.27 1.27)
					(thickness 0.15)
				)
				(justify left bottom)
				(hide yes)
			)
		)
		(property "Datasheet" ""
			(at 186.69 254 0)
			(effects
				(font
					(size 1.27 1.27)
					(thickness 0.15)
				)
				(justify left bottom)
				(hide yes)
			)
		)
		(property "Description" ""
			(at 177.8 241.3 0)
			(effects
				(font
					(size 1.27 1.27)
				)
				(hide yes)
			)
		)
		(property "Author" "Antmicro"
			(at 186.69 246.38 0)
			(effects
				(font
					(size 1.27 1.27)
					(thickness 0.15)
				)
				(justify left bottom)
				(hide yes)
			)
		)
		(property "License" "Apache-2.0"
			(at 186.69 248.92 0)
			(effects
				(font
					(size 1.27 1.27)
					(thickness 0.15)
				)
				(justify left bottom)
				(hide yes)
			)
		)
		(pin "1"
		)
		(instances
			(project "data-center-rdimm-ddr5-tester"
				(path ""
					(reference "#PWR071")
					(unit 1)
				)
			)
		)
	)
	(symbol
		(lib_id "antmicroCapacitors0402:C_1u_25V_0402")
		(at 95.25 172.72 90)
		(unit 1)
		(exclude_from_sim no)
		(in_bom yes)
		(on_board yes)
		(dnp no)
		(fields_autoplaced yes)
		(property "Reference" "C59"
			(at 97.79 168.9036 90)
			(effects
				(font
					(size 1.27 1.27)
					(thickness 0.15)
				)
				(justify right)
			)
		)
		(property "Value" "C_1u_25V_0402"
			(at 105.41 152.4 0)
			(effects
				(font
					(size 1.27 1.27)
					(thickness 0.15)
				)
				(justify left bottom)
				(hide yes)
			)
		)
		(property "Footprint" "antmicro-footprints:C_0402_1005Metric_EIA"
			(at 107.95 152.4 0)
			(effects
				(font
					(size 1.27 1.27)
					(thickness 0.15)
				)
				(justify left bottom)
				(hide yes)
			)
		)
		(property "Datasheet" "https://www.murata.com/products/productdetail?partno=GRM155R61E105KE11%23"
			(at 110.49 152.4 0)
			(effects
				(font
					(size 1.27 1.27)
					(thickness 0.15)
				)
				(justify left bottom)
				(hide yes)
			)
		)
		(property "Description" ""
			(at 95.25 172.72 0)
			(effects
				(font
					(size 1.27 1.27)
				)
				(hide yes)
			)
		)
		(property "MPN" "GRM155R61E105KE11J"
			(at 113.03 152.4 0)
			(effects
				(font
					(size 1.27 1.27)
					(thickness 0.15)
				)
				(justify left bottom)
				(hide yes)
			)
		)
		(property "Manufacturer" "Murata"
			(at 115.57 152.4 0)
			(effects
				(font
					(size 1.27 1.27)
					(thickness 0.15)
				)
				(justify left bottom)
				(hide yes)
			)
		)
		(property "License" "Apache-2.0"
			(at 118.11 152.4 0)
			(effects
				(font
					(size 1.27 1.27)
					(thickness 0.15)
				)
				(justify left bottom)
				(hide yes)
			)
		)
		(property "Author" "Antmicro"
			(at 120.65 152.4 0)
			(effects
				(font
					(size 1.27 1.27)
					(thickness 0.15)
				)
				(justify left bottom)
				(hide yes)
			)
		)
		(property "Val" "1u"
			(at 97.79 171.4436 90)
			(effects
				(font
					(size 1.27 1.27)
					(thickness 0.15)
				)
				(justify right)
			)
		)
		(property "Voltage" "25V"
			(at 123.19 152.4 0)
			(effects
				(font
					(size 1.27 1.27)
				)
				(justify left bottom)
				(hide yes)
			)
		)
		(property "Dielectric" "X5R"
			(at 125.73 152.4 0)
			(effects
				(font
					(size 1.27 1.27)
				)
				(justify left bottom)
				(hide yes)
			)
		)
		(pin "1"
		)
		(pin "2"
		)
		(instances
			(project "data-center-rdimm-ddr5-tester"
				(path ""
					(reference "C59")
					(unit 1)
				)
			)
		)
	)
	(symbol
		(lib_id "antmicropower:GND")
		(at 256.54 241.3 0)
		(unit 1)
		(exclude_from_sim no)
		(in_bom yes)
		(on_board yes)
		(dnp no)
		(fields_autoplaced yes)
		(property "Reference" "#PWR0137"
			(at 256.54 247.65 0)
			(effects
				(font
					(size 1.27 1.27)
				)
				(hide yes)
			)
		)
		(property "Value" "GND"
			(at 254.635 245.745 0)
			(effects
				(font
					(size 1.27 1.27)
					(thickness 0.15)
				)
				(justify left bottom)
			)
		)
		(property "Footprint" ""
			(at 265.43 248.92 0)
			(effects
				(font
					(size 1.27 1.27)
					(thickness 0.15)
				)
				(justify left bottom)
				(hide yes)
			)
		)
		(property "Datasheet" ""
			(at 265.43 254 0)
			(effects
				(font
					(size 1.27 1.27)
					(thickness 0.15)
				)
				(justify left bottom)
				(hide yes)
			)
		)
		(property "Description" ""
			(at 256.54 241.3 0)
			(effects
				(font
					(size 1.27 1.27)
				)
				(hide yes)
			)
		)
		(property "Author" "Antmicro"
			(at 265.43 246.38 0)
			(effects
				(font
					(size 1.27 1.27)
					(thickness 0.15)
				)
				(justify left bottom)
				(hide yes)
			)
		)
		(property "License" "Apache-2.0"
			(at 265.43 248.92 0)
			(effects
				(font
					(size 1.27 1.27)
					(thickness 0.15)
				)
				(justify left bottom)
				(hide yes)
			)
		)
		(pin "1"
		)
		(instances
			(project "data-center-rdimm-ddr5-tester"
				(path ""
					(reference "#PWR0137")
					(unit 1)
				)
			)
		)
	)
	(symbol
		(lib_id "antmicroCapacitors0402:C_10u_10V_0402")
		(at 44.45 92.71 90)
		(unit 1)
		(exclude_from_sim no)
		(in_bom yes)
		(on_board yes)
		(dnp no)
		(fields_autoplaced yes)
		(property "Reference" "C67"
			(at 47.625 88.8936 90)
			(effects
				(font
					(size 1.27 1.27)
					(thickness 0.15)
				)
				(justify right)
			)
		)
		(property "Value" "C_10u_10V_0402"
			(at 54.61 72.39 0)
			(effects
				(font
					(size 1.27 1.27)
					(thickness 0.15)
				)
				(justify left bottom)
				(hide yes)
			)
		)
		(property "Footprint" "antmicro-footprints:C_0402_1005Metric_EIA"
			(at 57.15 72.39 0)
			(effects
				(font
					(size 1.27 1.27)
					(thickness 0.15)
				)
				(justify left bottom)
				(hide yes)
			)
		)
		(property "Datasheet" "https://www.murata.com/products/productdetail?partno=GRM155R61A106ME11%23"
			(at 59.69 72.39 0)
			(effects
				(font
					(size 1.27 1.27)
					(thickness 0.15)
				)
				(justify left bottom)
				(hide yes)
			)
		)
		(property "Description" ""
			(at 44.45 92.71 0)
			(effects
				(font
					(size 1.27 1.27)
				)
				(hide yes)
			)
		)
		(property "MPN" "GRM155R61A106ME11D"
			(at 62.23 72.39 0)
			(effects
				(font
					(size 1.27 1.27)
					(thickness 0.15)
				)
				(justify left bottom)
				(hide yes)
			)
		)
		(property "Manufacturer" "Murata"
			(at 64.77 72.39 0)
			(effects
				(font
					(size 1.27 1.27)
					(thickness 0.15)
				)
				(justify left bottom)
				(hide yes)
			)
		)
		(property "License" "Apache-2.0"
			(at 67.31 72.39 0)
			(effects
				(font
					(size 1.27 1.27)
					(thickness 0.15)
				)
				(justify left bottom)
				(hide yes)
			)
		)
		(property "Author" "Antmicro"
			(at 69.85 72.39 0)
			(effects
				(font
					(size 1.27 1.27)
					(thickness 0.15)
				)
				(justify left bottom)
				(hide yes)
			)
		)
		(property "Val" "10u"
			(at 47.625 91.4336 90)
			(effects
				(font
					(size 1.27 1.27)
					(thickness 0.15)
				)
				(justify right)
			)
		)
		(property "Voltage" "10V"
			(at 72.39 72.39 0)
			(effects
				(font
					(size 1.27 1.27)
				)
				(justify left bottom)
				(hide yes)
			)
		)
		(property "Dielectric" "X5R"
			(at 74.93 72.39 0)
			(effects
				(font
					(size 1.27 1.27)
				)
				(justify left bottom)
				(hide yes)
			)
		)
		(pin "1"
		)
		(pin "2"
		)
		(instances
			(project "data-center-rdimm-ddr5-tester"
				(path ""
					(reference "C67")
					(unit 1)
				)
			)
		)
	)
	(symbol
		(lib_id "antmicroCapacitorspol:C_Pol_1m_2.5V_KEMET-T520-D")
		(at 38.1 60.96 270)
		(unit 1)
		(exclude_from_sim no)
		(in_bom yes)
		(on_board yes)
		(dnp no)
		(fields_autoplaced yes)
		(property "Reference" "C12"
			(at 40.513 62.136 90)
			(effects
				(font
					(size 1.27 1.27)
					(thickness 0.15)
				)
				(justify left)
			)
		)
		(property "Value" "C_Pol_1m_2.5V_KEMET-T520-D"
			(at 35.56 74.93 0)
			(effects
				(font
					(size 1.27 1.27)
					(thickness 0.15)
				)
				(justify left bottom)
				(hide yes)
			)
		)
		(property "Footprint" "antmicro-footprints:C_Pol_EIA-D"
			(at 30.48 74.93 0)
			(effects
				(font
					(size 1.27 1.27)
					(thickness 0.15)
				)
				(justify left bottom)
				(hide yes)
			)
		)
		(property "Datasheet" "https://www.kemet.com/en/us/capacitors/product/T520D108M2R5ATE030.html"
			(at 27.94 74.93 0)
			(effects
				(font
					(size 1.27 1.27)
					(thickness 0.15)
				)
				(justify left bottom)
				(hide yes)
			)
		)
		(property "Description" ""
			(at 38.1 60.96 0)
			(effects
				(font
					(size 1.27 1.27)
				)
				(hide yes)
			)
		)
		(property "MPN" "T520D108M2R5ATE030"
			(at 25.4 74.93 0)
			(effects
				(font
					(size 1.27 1.27)
					(thickness 0.15)
				)
				(justify left bottom)
				(hide yes)
			)
		)
		(property "Manufacturer" "KEMET"
			(at 22.86 74.93 0)
			(effects
				(font
					(size 1.27 1.27)
					(thickness 0.15)
				)
				(justify left bottom)
				(hide yes)
			)
		)
		(property "License" "Apache-2.0"
			(at 20.32 74.93 0)
			(effects
				(font
					(size 1.27 1.27)
					(thickness 0.15)
				)
				(justify left bottom)
				(hide yes)
			)
		)
		(property "Author" "Antmicro"
			(at 17.78 74.93 0)
			(effects
				(font
					(size 1.27 1.27)
					(thickness 0.15)
				)
				(justify left bottom)
				(hide yes)
			)
		)
		(property "Val" "1000u"
			(at 40.513 64.6597 90)
			(effects
				(font
					(size 1.27 1.27)
					(thickness 0.15)
				)
				(justify left)
			)
		)
		(property "Voltage" "2.5V"
			(at 15.24 74.93 0)
			(effects
				(font
					(size 1.27 1.27)
				)
				(justify left bottom)
				(hide yes)
			)
		)
		(property "Dielectric" "template_dielectric"
			(at 12.7 74.93 0)
			(effects
				(font
					(size 1.27 1.27)
				)
				(justify left bottom)
				(hide yes)
			)
		)
		(pin "1"
		)
		(pin "2"
		)
		(instances
			(project "data-center-rdimm-ddr5-tester"
				(path ""
					(reference "C12")
					(unit 1)
				)
			)
		)
	)
	(symbol
		(lib_id "antmicropower:GND")
		(at 45.72 120.65 0)
		(unit 1)
		(exclude_from_sim no)
		(in_bom yes)
		(on_board yes)
		(dnp no)
		(fields_autoplaced yes)
		(property "Reference" "#PWR066"
			(at 45.72 127 0)
			(effects
				(font
					(size 1.27 1.27)
				)
				(hide yes)
			)
		)
		(property "Value" "GND"
			(at 43.815 125.095 0)
			(effects
				(font
					(size 1.27 1.27)
					(thickness 0.15)
				)
				(justify left bottom)
			)
		)
		(property "Footprint" ""
			(at 54.61 128.27 0)
			(effects
				(font
					(size 1.27 1.27)
					(thickness 0.15)
				)
				(justify left bottom)
				(hide yes)
			)
		)
		(property "Datasheet" ""
			(at 54.61 133.35 0)
			(effects
				(font
					(size 1.27 1.27)
					(thickness 0.15)
				)
				(justify left bottom)
				(hide yes)
			)
		)
		(property "Description" ""
			(at 45.72 120.65 0)
			(effects
				(font
					(size 1.27 1.27)
				)
				(hide yes)
			)
		)
		(property "Author" "Antmicro"
			(at 54.61 125.73 0)
			(effects
				(font
					(size 1.27 1.27)
					(thickness 0.15)
				)
				(justify left bottom)
				(hide yes)
			)
		)
		(property "License" "Apache-2.0"
			(at 54.61 128.27 0)
			(effects
				(font
					(size 1.27 1.27)
					(thickness 0.15)
				)
				(justify left bottom)
				(hide yes)
			)
		)
		(pin "1"
		)
		(instances
			(project "data-center-rdimm-ddr5-tester"
				(path ""
					(reference "#PWR066")
					(unit 1)
				)
			)
		)
	)
	(symbol
		(lib_id "antmicroCapacitors0603:C_47u_0603")
		(at 256.54 233.68 270)
		(unit 1)
		(exclude_from_sim no)
		(in_bom yes)
		(on_board yes)
		(dnp no)
		(property "Reference" "C85"
			(at 256.54 234.315 90)
			(effects
				(font
					(size 1.27 1.27)
				)
				(justify left)
			)
		)
		(property "Value" "C_47u_0603"
			(at 246.38 254 0)
			(effects
				(font
					(size 1.27 1.27)
					(thickness 0.15)
				)
				(justify left bottom)
				(hide yes)
			)
		)
		(property "Footprint" "antmicro-footprints:C_0603_1608Metric"
			(at 243.84 254 0)
			(effects
				(font
					(size 1.27 1.27)
					(thickness 0.15)
				)
				(justify left bottom)
				(hide yes)
			)
		)
		(property "Datasheet" "https://www.murata.com/products/productdetail?partno=GRM188R60J476ME15%23"
			(at 241.3 254 0)
			(effects
				(font
					(size 1.27 1.27)
					(thickness 0.15)
				)
				(justify left bottom)
				(hide yes)
			)
		)
		(property "Description" ""
			(at 256.54 233.68 0)
			(effects
				(font
					(size 1.27 1.27)
				)
				(hide yes)
			)
		)
		(property "Manufacturer" "Murata"
			(at 236.22 254 0)
			(effects
				(font
					(size 1.27 1.27)
					(thickness 0.15)
				)
				(justify left bottom)
				(hide yes)
			)
		)
		(property "MPN" "GRM188R60J476ME15D"
			(at 238.76 254 0)
			(effects
				(font
					(size 1.27 1.27)
					(thickness 0.15)
				)
				(justify left bottom)
				(hide yes)
			)
		)
		(property "Val" "47u"
			(at 256.54 238.125 90)
			(effects
				(font
					(size 1.27 1.27)
					(thickness 0.15)
				)
				(justify left)
			)
		)
		(property "License" "Apache-2.0"
			(at 233.68 254 0)
			(effects
				(font
					(size 1.27 1.27)
					(thickness 0.15)
				)
				(justify left bottom)
				(hide yes)
			)
		)
		(property "Author" "Antmicro"
			(at 231.14 254 0)
			(effects
				(font
					(size 1.27 1.27)
					(thickness 0.15)
				)
				(justify left bottom)
				(hide yes)
			)
		)
		(property "Voltage" ""
			(at 228.6 254 0)
			(effects
				(font
					(size 1.27 1.27)
				)
				(justify left bottom)
				(hide yes)
			)
		)
		(property "Dielectric" ""
			(at 226.06 254 0)
			(effects
				(font
					(size 1.27 1.27)
				)
				(justify left bottom)
				(hide yes)
			)
		)
		(pin "1"
		)
		(pin "2"
		)
		(instances
			(project "data-center-rdimm-ddr5-tester"
				(path ""
					(reference "C85")
					(unit 1)
				)
			)
		)
	)
	(symbol
		(lib_id "antmicropower:GND")
		(at 60.96 148.59 0)
		(unit 1)
		(exclude_from_sim no)
		(in_bom yes)
		(on_board yes)
		(dnp no)
		(fields_autoplaced yes)
		(property "Reference" "#PWR086"
			(at 60.96 154.94 0)
			(effects
				(font
					(size 1.27 1.27)
				)
				(hide yes)
			)
		)
		(property "Value" "GND"
			(at 59.055 153.035 0)
			(effects
				(font
					(size 1.27 1.27)
					(thickness 0.15)
				)
				(justify left bottom)
			)
		)
		(property "Footprint" ""
			(at 69.85 156.21 0)
			(effects
				(font
					(size 1.27 1.27)
					(thickness 0.15)
				)
				(justify left bottom)
				(hide yes)
			)
		)
		(property "Datasheet" ""
			(at 69.85 161.29 0)
			(effects
				(font
					(size 1.27 1.27)
					(thickness 0.15)
				)
				(justify left bottom)
				(hide yes)
			)
		)
		(property "Description" ""
			(at 60.96 148.59 0)
			(effects
				(font
					(size 1.27 1.27)
				)
				(hide yes)
			)
		)
		(property "Author" "Antmicro"
			(at 69.85 153.67 0)
			(effects
				(font
					(size 1.27 1.27)
					(thickness 0.15)
				)
				(justify left bottom)
				(hide yes)
			)
		)
		(property "License" "Apache-2.0"
			(at 69.85 156.21 0)
			(effects
				(font
					(size 1.27 1.27)
					(thickness 0.15)
				)
				(justify left bottom)
				(hide yes)
			)
		)
		(pin "1"
		)
		(instances
			(project "data-center-rdimm-ddr5-tester"
				(path ""
					(reference "#PWR086")
					(unit 1)
				)
			)
		)
	)
	(symbol
		(lib_id "antmicroCapacitorsmisc:C_100u_0805")
		(at 71.12 66.04 90)
		(unit 1)
		(exclude_from_sim no)
		(in_bom yes)
		(on_board yes)
		(dnp no)
		(fields_autoplaced yes)
		(property "Reference" "C54"
			(at 73.66 62.2236 90)
			(effects
				(font
					(size 1.27 1.27)
					(thickness 0.15)
				)
				(justify right)
			)
		)
		(property "Value" "C_100u_0805"
			(at 81.28 45.72 0)
			(effects
				(font
					(size 1.27 1.27)
					(thickness 0.15)
				)
				(justify left bottom)
				(hide yes)
			)
		)
		(property "Footprint" "antmicro-footprints:C_0805_2012Metric"
			(at 83.82 45.72 0)
			(effects
				(font
					(size 1.27 1.27)
					(thickness 0.15)
				)
				(justify left bottom)
				(hide yes)
			)
		)
		(property "Datasheet" "https://www.murata.com/products/productdetail?partno=GRM21BR60J107ME15%23"
			(at 86.36 45.72 0)
			(effects
				(font
					(size 1.27 1.27)
					(thickness 0.15)
				)
				(justify left bottom)
				(hide yes)
			)
		)
		(property "Description" ""
			(at 71.12 66.04 0)
			(effects
				(font
					(size 1.27 1.27)
				)
				(hide yes)
			)
		)
		(property "MPN" "GRM21BR60J107ME15L"
			(at 88.9 45.72 0)
			(effects
				(font
					(size 1.27 1.27)
					(thickness 0.15)
				)
				(justify left bottom)
				(hide yes)
			)
		)
		(property "Manufacturer" "Murata"
			(at 91.44 45.72 0)
			(effects
				(font
					(size 1.27 1.27)
					(thickness 0.15)
				)
				(justify left bottom)
				(hide yes)
			)
		)
		(property "License" "Apache-2.0"
			(at 93.98 45.72 0)
			(effects
				(font
					(size 1.27 1.27)
					(thickness 0.15)
				)
				(justify left bottom)
				(hide yes)
			)
		)
		(property "Author" "Antmicro"
			(at 96.52 45.72 0)
			(effects
				(font
					(size 1.27 1.27)
					(thickness 0.15)
				)
				(justify left bottom)
				(hide yes)
			)
		)
		(property "Val" "100u"
			(at 73.66 64.7636 90)
			(effects
				(font
					(size 1.27 1.27)
					(thickness 0.15)
				)
				(justify right)
			)
		)
		(property "Voltage" ""
			(at 99.06 45.72 0)
			(effects
				(font
					(size 1.27 1.27)
				)
				(justify left bottom)
				(hide yes)
			)
		)
		(property "Dielectric" ""
			(at 101.6 45.72 0)
			(effects
				(font
					(size 1.27 1.27)
				)
				(justify left bottom)
				(hide yes)
			)
		)
		(property "Public" "False"
			(at 104.14 45.72 0)
			(effects
				(font
					(size 1.27 1.27)
				)
				(justify left bottom)
				(hide yes)
			)
		)
		(pin "1"
		)
		(pin "2"
		)
		(instances
			(project "data-center-rdimm-ddr5-tester"
				(path ""
					(reference "C54")
					(unit 1)
				)
			)
		)
	)
	(symbol
		(lib_id "antmicropower:GND")
		(at 88.9 67.31 0)
		(mirror y)
		(unit 1)
		(exclude_from_sim no)
		(in_bom yes)
		(on_board yes)
		(dnp no)
		(fields_autoplaced yes)
		(property "Reference" "#PWR050"
			(at 88.9 73.66 0)
			(effects
				(font
					(size 1.27 1.27)
				)
				(hide yes)
			)
		)
		(property "Value" "GND"
			(at 90.805 71.755 0)
			(effects
				(font
					(size 1.27 1.27)
					(thickness 0.15)
				)
				(justify left bottom)
			)
		)
		(property "Footprint" ""
			(at 80.01 74.93 0)
			(effects
				(font
					(size 1.27 1.27)
					(thickness 0.15)
				)
				(justify left bottom)
				(hide yes)
			)
		)
		(property "Datasheet" ""
			(at 80.01 80.01 0)
			(effects
				(font
					(size 1.27 1.27)
					(thickness 0.15)
				)
				(justify left bottom)
				(hide yes)
			)
		)
		(property "Description" ""
			(at 88.9 67.31 0)
			(effects
				(font
					(size 1.27 1.27)
				)
				(hide yes)
			)
		)
		(property "Author" "Antmicro"
			(at 80.01 72.39 0)
			(effects
				(font
					(size 1.27 1.27)
					(thickness 0.15)
				)
				(justify left bottom)
				(hide yes)
			)
		)
		(property "License" "Apache-2.0"
			(at 80.01 74.93 0)
			(effects
				(font
					(size 1.27 1.27)
					(thickness 0.15)
				)
				(justify left bottom)
				(hide yes)
			)
		)
		(pin "1"
		)
		(instances
			(project "data-center-rdimm-ddr5-tester"
				(path ""
					(reference "#PWR050")
					(unit 1)
				)
			)
		)
	)
	(symbol
		(lib_id "antmicroCapacitorspol:C_Pol_330u_6.3V_KEMET-T520-B")
		(at 60.96 60.96 270)
		(unit 1)
		(exclude_from_sim no)
		(in_bom yes)
		(on_board yes)
		(dnp no)
		(property "Reference" "C25"
			(at 63.5 62.23 90)
			(effects
				(font
					(size 1.27 1.27)
					(thickness 0.15)
				)
				(justify left)
			)
		)
		(property "Value" "C_Pol_330u_6.3V_KEMET-T520-B"
			(at 58.42 74.93 0)
			(effects
				(font
					(size 1.27 1.27)
					(thickness 0.15)
				)
				(justify left bottom)
				(hide yes)
			)
		)
		(property "Footprint" "antmicro-footprints:C_Pol_EIA-B"
			(at 53.34 74.93 0)
			(effects
				(font
					(size 1.27 1.27)
					(thickness 0.15)
				)
				(justify left bottom)
				(hide yes)
			)
		)
		(property "Datasheet" "https://www.kemet.com/en/us/capacitors/product/T520B337M006ATE040.html"
			(at 50.8 74.93 0)
			(effects
				(font
					(size 1.27 1.27)
					(thickness 0.15)
				)
				(justify left bottom)
				(hide yes)
			)
		)
		(property "Description" ""
			(at 60.96 60.96 0)
			(effects
				(font
					(size 1.27 1.27)
				)
				(hide yes)
			)
		)
		(property "Val" "330u"
			(at 63.5 64.7537 90)
			(effects
				(font
					(size 1.27 1.27)
					(thickness 0.15)
				)
				(justify left)
			)
		)
		(property "MPN" "T520B337M006ATE040"
			(at 48.26 74.93 0)
			(effects
				(font
					(size 1.27 1.27)
					(thickness 0.15)
				)
				(justify left bottom)
				(hide yes)
			)
		)
		(property "Manufacturer" "KEMET"
			(at 45.72 74.93 0)
			(effects
				(font
					(size 1.27 1.27)
					(thickness 0.15)
				)
				(justify left bottom)
				(hide yes)
			)
		)
		(property "License" "Apache-2.0"
			(at 43.18 74.93 0)
			(effects
				(font
					(size 1.27 1.27)
					(thickness 0.15)
				)
				(justify left bottom)
				(hide yes)
			)
		)
		(property "Author" "Antmicro"
			(at 40.64 74.93 0)
			(effects
				(font
					(size 1.27 1.27)
					(thickness 0.15)
				)
				(justify left bottom)
				(hide yes)
			)
		)
		(property "Voltage" "6.3V"
			(at 38.1 74.93 0)
			(effects
				(font
					(size 1.27 1.27)
				)
				(justify left bottom)
				(hide yes)
			)
		)
		(property "Dielectric" "template_dielectric"
			(at 35.56 74.93 0)
			(effects
				(font
					(size 1.27 1.27)
				)
				(justify left bottom)
				(hide yes)
			)
		)
		(pin "1"
		)
		(pin "2"
		)
		(instances
			(project "data-center-rdimm-ddr5-tester"
				(path ""
					(reference "C25")
					(unit 1)
				)
			)
		)
	)
	(symbol
		(lib_id "antmicropower:GND")
		(at 373.38 134.62 0)
		(unit 1)
		(exclude_from_sim no)
		(in_bom yes)
		(on_board yes)
		(dnp no)
		(fields_autoplaced yes)
		(property "Reference" "#PWR0157"
			(at 373.38 140.97 0)
			(effects
				(font
					(size 1.27 1.27)
				)
				(hide yes)
			)
		)
		(property "Value" "GND"
			(at 371.475 139.065 0)
			(effects
				(font
					(size 1.27 1.27)
					(thickness 0.15)
				)
				(justify left bottom)
			)
		)
		(property "Footprint" ""
			(at 382.27 142.24 0)
			(effects
				(font
					(size 1.27 1.27)
					(thickness 0.15)
				)
				(justify left bottom)
				(hide yes)
			)
		)
		(property "Datasheet" ""
			(at 382.27 147.32 0)
			(effects
				(font
					(size 1.27 1.27)
					(thickness 0.15)
				)
				(justify left bottom)
				(hide yes)
			)
		)
		(property "Description" ""
			(at 373.38 134.62 0)
			(effects
				(font
					(size 1.27 1.27)
				)
				(hide yes)
			)
		)
		(property "Author" "Antmicro"
			(at 382.27 139.7 0)
			(effects
				(font
					(size 1.27 1.27)
					(thickness 0.15)
				)
				(justify left bottom)
				(hide yes)
			)
		)
		(property "License" "Apache-2.0"
			(at 382.27 142.24 0)
			(effects
				(font
					(size 1.27 1.27)
					(thickness 0.15)
				)
				(justify left bottom)
				(hide yes)
			)
		)
		(pin "1"
		)
		(instances
			(project "data-center-rdimm-ddr5-tester"
				(path ""
					(reference "#PWR0157")
					(unit 1)
				)
			)
		)
	)
	(symbol
		(lib_id "antmicroResistors0402:R_100R_0402")
		(at 274.32 115.57 90)
		(mirror x)
		(unit 1)
		(exclude_from_sim no)
		(in_bom yes)
		(on_board yes)
		(dnp no)
		(fields_autoplaced yes)
		(property "Reference" "R36"
			(at 276.225 119.38 90)
			(effects
				(font
					(size 1.27 1.27)
				)
				(justify right)
			)
		)
		(property "Value" "R_100R_0402"
			(at 287.02 135.89 0)
			(effects
				(font
					(size 1.27 1.27)
					(thickness 0.15)
				)
				(justify left bottom)
				(hide yes)
			)
		)
		(property "Footprint" "antmicro-footprints:R_0402_1005Metric_EIA"
			(at 289.56 135.89 0)
			(effects
				(font
					(size 1.27 1.27)
					(thickness 0.15)
				)
				(justify left bottom)
				(hide yes)
			)
		)
		(property "Datasheet" "https://www.bourns.com/docs/product-datasheets/cr.pdf"
			(at 292.1 135.89 0)
			(effects
				(font
					(size 1.27 1.27)
					(thickness 0.15)
				)
				(justify left bottom)
				(hide yes)
			)
		)
		(property "Description" ""
			(at 274.32 115.57 0)
			(effects
				(font
					(size 1.27 1.27)
				)
				(hide yes)
			)
		)
		(property "Manufacturer" "Bourns"
			(at 297.18 135.89 0)
			(effects
				(font
					(size 1.27 1.27)
					(thickness 0.15)
				)
				(justify left bottom)
				(hide yes)
			)
		)
		(property "MPN" "CR0402-FX-1000GLF"
			(at 294.64 135.89 0)
			(effects
				(font
					(size 1.27 1.27)
					(thickness 0.15)
				)
				(justify left bottom)
				(hide yes)
			)
		)
		(property "Val" "100R"
			(at 276.225 116.2051 90)
			(effects
				(font
					(size 1.27 1.27)
					(thickness 0.15)
				)
				(justify right)
			)
		)
		(property "License" "Apache-2.0"
			(at 299.72 135.89 0)
			(effects
				(font
					(size 1.27 1.27)
					(thickness 0.15)
				)
				(justify left bottom)
				(hide yes)
			)
		)
		(property "Author" "Antmicro"
			(at 302.26 135.89 0)
			(effects
				(font
					(size 1.27 1.27)
					(thickness 0.15)
				)
				(justify left bottom)
				(hide yes)
			)
		)
		(property "Tolerance" "1%"
			(at 284.48 135.89 0)
			(effects
				(font
					(size 1.27 1.27)
				)
				(justify left bottom)
				(hide yes)
			)
		)
		(pin "1"
		)
		(pin "2"
		)
		(instances
			(project "data-center-rdimm-ddr5-tester"
				(path ""
					(reference "R36")
					(unit 1)
				)
			)
		)
	)
	(symbol
		(lib_id "antmicropower:GND")
		(at 345.44 175.26 0)
		(unit 1)
		(exclude_from_sim no)
		(in_bom yes)
		(on_board yes)
		(dnp no)
		(fields_autoplaced yes)
		(property "Reference" "#PWR0147"
			(at 345.44 181.61 0)
			(effects
				(font
					(size 1.27 1.27)
				)
				(hide yes)
			)
		)
		(property "Value" "GND"
			(at 343.535 179.705 0)
			(effects
				(font
					(size 1.27 1.27)
					(thickness 0.15)
				)
				(justify left bottom)
			)
		)
		(property "Footprint" ""
			(at 354.33 182.88 0)
			(effects
				(font
					(size 1.27 1.27)
					(thickness 0.15)
				)
				(justify left bottom)
				(hide yes)
			)
		)
		(property "Datasheet" ""
			(at 354.33 187.96 0)
			(effects
				(font
					(size 1.27 1.27)
					(thickness 0.15)
				)
				(justify left bottom)
				(hide yes)
			)
		)
		(property "Description" ""
			(at 345.44 175.26 0)
			(effects
				(font
					(size 1.27 1.27)
				)
				(hide yes)
			)
		)
		(property "Author" "Antmicro"
			(at 354.33 180.34 0)
			(effects
				(font
					(size 1.27 1.27)
					(thickness 0.15)
				)
				(justify left bottom)
				(hide yes)
			)
		)
		(property "License" "Apache-2.0"
			(at 354.33 182.88 0)
			(effects
				(font
					(size 1.27 1.27)
					(thickness 0.15)
				)
				(justify left bottom)
				(hide yes)
			)
		)
		(pin "1"
		)
		(instances
			(project "data-center-rdimm-ddr5-tester"
				(path ""
					(reference "#PWR0147")
					(unit 1)
				)
			)
		)
	)
	(symbol
		(lib_id "antmicropower:GND")
		(at 346.71 66.04 0)
		(unit 1)
		(exclude_from_sim no)
		(in_bom yes)
		(on_board yes)
		(dnp no)
		(fields_autoplaced yes)
		(property "Reference" "#PWR0163"
			(at 346.71 72.39 0)
			(effects
				(font
					(size 1.27 1.27)
				)
				(hide yes)
			)
		)
		(property "Value" "GND"
			(at 344.805 70.485 0)
			(effects
				(font
					(size 1.27 1.27)
					(thickness 0.15)
				)
				(justify left bottom)
			)
		)
		(property "Footprint" ""
			(at 355.6 73.66 0)
			(effects
				(font
					(size 1.27 1.27)
					(thickness 0.15)
				)
				(justify left bottom)
				(hide yes)
			)
		)
		(property "Datasheet" ""
			(at 355.6 78.74 0)
			(effects
				(font
					(size 1.27 1.27)
					(thickness 0.15)
				)
				(justify left bottom)
				(hide yes)
			)
		)
		(property "Description" ""
			(at 346.71 66.04 0)
			(effects
				(font
					(size 1.27 1.27)
				)
				(hide yes)
			)
		)
		(property "Author" "Antmicro"
			(at 355.6 71.12 0)
			(effects
				(font
					(size 1.27 1.27)
					(thickness 0.15)
				)
				(justify left bottom)
				(hide yes)
			)
		)
		(property "License" "Apache-2.0"
			(at 355.6 73.66 0)
			(effects
				(font
					(size 1.27 1.27)
					(thickness 0.15)
				)
				(justify left bottom)
				(hide yes)
			)
		)
		(pin "1"
		)
		(instances
			(project "data-center-rdimm-ddr5-tester"
				(path ""
					(reference "#PWR0163")
					(unit 1)
				)
			)
		)
	)
	(symbol
		(lib_id "antmicropower:GND")
		(at 36.83 120.65 0)
		(unit 1)
		(exclude_from_sim no)
		(in_bom yes)
		(on_board yes)
		(dnp no)
		(fields_autoplaced yes)
		(property "Reference" "#PWR056"
			(at 36.83 127 0)
			(effects
				(font
					(size 1.27 1.27)
				)
				(hide yes)
			)
		)
		(property "Value" "GND"
			(at 34.925 125.095 0)
			(effects
				(font
					(size 1.27 1.27)
					(thickness 0.15)
				)
				(justify left bottom)
			)
		)
		(property "Footprint" ""
			(at 45.72 128.27 0)
			(effects
				(font
					(size 1.27 1.27)
					(thickness 0.15)
				)
				(justify left bottom)
				(hide yes)
			)
		)
		(property "Datasheet" ""
			(at 45.72 133.35 0)
			(effects
				(font
					(size 1.27 1.27)
					(thickness 0.15)
				)
				(justify left bottom)
				(hide yes)
			)
		)
		(property "Description" ""
			(at 36.83 120.65 0)
			(effects
				(font
					(size 1.27 1.27)
				)
				(hide yes)
			)
		)
		(property "Author" "Antmicro"
			(at 45.72 125.73 0)
			(effects
				(font
					(size 1.27 1.27)
					(thickness 0.15)
				)
				(justify left bottom)
				(hide yes)
			)
		)
		(property "License" "Apache-2.0"
			(at 45.72 128.27 0)
			(effects
				(font
					(size 1.27 1.27)
					(thickness 0.15)
				)
				(justify left bottom)
				(hide yes)
			)
		)
		(pin "1"
		)
		(instances
			(project "data-center-rdimm-ddr5-tester"
				(path ""
					(reference "#PWR056")
					(unit 1)
				)
			)
		)
	)
	(symbol
		(lib_id "antmicropower:+0V85")
		(at 36.83 162.56 0)
		(unit 1)
		(exclude_from_sim no)
		(in_bom yes)
		(on_board yes)
		(dnp no)
		(property "Reference" "#PWR0463"
			(at 36.83 166.37 0)
			(effects
				(font
					(size 1.27 1.27)
				)
				(hide yes)
			)
		)
		(property "Value" "+0V85"
			(at 40.005 157.48 0)
			(effects
				(font
					(size 1.27 1.27)
				)
				(justify right)
			)
		)
		(property "Footprint" ""
			(at 36.83 162.56 0)
			(effects
				(font
					(size 1.27 1.27)
				)
				(hide yes)
			)
		)
		(property "Datasheet" ""
			(at 36.83 162.56 0)
			(effects
				(font
					(size 1.27 1.27)
				)
				(hide yes)
			)
		)
		(property "Description" ""
			(at 36.83 162.56 0)
			(effects
				(font
					(size 1.27 1.27)
				)
				(hide yes)
			)
		)
		(pin "1"
		)
		(instances
			(project "data-center-rdimm-ddr5-tester"
				(path ""
					(reference "#PWR0463")
					(unit 1)
				)
			)
		)
	)
	(symbol
		(lib_id "antmicropower:+1V2_MGTAVTT")
		(at 224.79 100.33 0)
		(unit 1)
		(exclude_from_sim no)
		(in_bom yes)
		(on_board yes)
		(dnp no)
		(fields_autoplaced yes)
		(property "Reference" "#PWR028"
			(at 224.79 104.14 0)
			(effects
				(font
					(size 1.27 1.27)
				)
				(hide yes)
			)
		)
		(property "Value" "+1V2_MGTAVTT"
			(at 224.79 95.885 0)
			(effects
				(font
					(size 1.27 1.27)
				)
			)
		)
		(property "Footprint" ""
			(at 224.79 100.33 0)
			(effects
				(font
					(size 1.27 1.27)
				)
				(hide yes)
			)
		)
		(property "Datasheet" ""
			(at 224.79 100.33 0)
			(effects
				(font
					(size 1.27 1.27)
				)
				(hide yes)
			)
		)
		(property "Description" ""
			(at 224.79 100.33 0)
			(effects
				(font
					(size 1.27 1.27)
				)
				(hide yes)
			)
		)
		(pin "1"
		)
		(instances
			(project "data-center-rdimm-ddr5-tester"
				(path ""
					(reference "#PWR028")
					(unit 1)
				)
			)
		)
	)
	(symbol
		(lib_id "antmicroCapacitors0402:C_100n_0402")
		(at 171.45 240.03 90)
		(unit 1)
		(exclude_from_sim no)
		(in_bom yes)
		(on_board yes)
		(dnp no)
		(property "Reference" "C20"
			(at 175.895 235.585 90)
			(effects
				(font
					(size 1.27 1.27)
					(thickness 0.15)
				)
				(justify left)
			)
		)
		(property "Value" "C_100n_0402"
			(at 181.61 219.71 0)
			(effects
				(font
					(size 1.27 1.27)
					(thickness 0.15)
				)
				(justify left bottom)
				(hide yes)
			)
		)
		(property "Footprint" "antmicro-footprints:C_0402_1005Metric_EIA"
			(at 184.15 219.71 0)
			(effects
				(font
					(size 1.27 1.27)
					(thickness 0.15)
				)
				(justify left bottom)
				(hide yes)
			)
		)
		(property "Datasheet" "https://www.murata.com/products/productdetail?partno=GRM155R61H104KE14%23"
			(at 186.69 219.71 0)
			(effects
				(font
					(size 1.27 1.27)
					(thickness 0.15)
				)
				(justify left bottom)
				(hide yes)
			)
		)
		(property "Description" ""
			(at 171.45 240.03 0)
			(effects
				(font
					(size 1.27 1.27)
				)
				(hide yes)
			)
		)
		(property "MPN" "GRM155R61H104KE14D"
			(at 189.23 219.71 0)
			(effects
				(font
					(size 1.27 1.27)
					(thickness 0.15)
				)
				(justify left bottom)
				(hide yes)
			)
		)
		(property "Manufacturer" "Murata"
			(at 191.77 219.71 0)
			(effects
				(font
					(size 1.27 1.27)
					(thickness 0.15)
				)
				(justify left bottom)
				(hide yes)
			)
		)
		(property "License" "Apache-2.0"
			(at 194.31 219.71 0)
			(effects
				(font
					(size 1.27 1.27)
					(thickness 0.15)
				)
				(justify left bottom)
				(hide yes)
			)
		)
		(property "Author" "Antmicro"
			(at 196.85 219.71 0)
			(effects
				(font
					(size 1.27 1.27)
					(thickness 0.15)
				)
				(justify left bottom)
				(hide yes)
			)
		)
		(property "Val" "100n"
			(at 177.165 239.395 90)
			(effects
				(font
					(size 1.27 1.27)
					(thickness 0.15)
				)
				(justify left)
			)
		)
		(property "Voltage" "50V"
			(at 199.39 219.71 0)
			(effects
				(font
					(size 1.27 1.27)
				)
				(justify left bottom)
				(hide yes)
			)
		)
		(property "Dielectric" "X5R"
			(at 201.93 219.71 0)
			(effects
				(font
					(size 1.27 1.27)
				)
				(justify left bottom)
				(hide yes)
			)
		)
		(pin "1"
		)
		(pin "2"
		)
		(instances
			(project "data-center-rdimm-ddr5-tester"
				(path ""
					(reference "C20")
					(unit 1)
				)
			)
		)
	)
	(symbol
		(lib_id "antmicropower:GND")
		(at 198.12 241.3 0)
		(unit 1)
		(exclude_from_sim no)
		(in_bom yes)
		(on_board yes)
		(dnp no)
		(fields_autoplaced yes)
		(property "Reference" "#PWR0107"
			(at 198.12 247.65 0)
			(effects
				(font
					(size 1.27 1.27)
				)
				(hide yes)
			)
		)
		(property "Value" "GND"
			(at 196.215 245.745 0)
			(effects
				(font
					(size 1.27 1.27)
					(thickness 0.15)
				)
				(justify left bottom)
			)
		)
		(property "Footprint" ""
			(at 207.01 248.92 0)
			(effects
				(font
					(size 1.27 1.27)
					(thickness 0.15)
				)
				(justify left bottom)
				(hide yes)
			)
		)
		(property "Datasheet" ""
			(at 207.01 254 0)
			(effects
				(font
					(size 1.27 1.27)
					(thickness 0.15)
				)
				(justify left bottom)
				(hide yes)
			)
		)
		(property "Description" ""
			(at 198.12 241.3 0)
			(effects
				(font
					(size 1.27 1.27)
				)
				(hide yes)
			)
		)
		(property "Author" "Antmicro"
			(at 207.01 246.38 0)
			(effects
				(font
					(size 1.27 1.27)
					(thickness 0.15)
				)
				(justify left bottom)
				(hide yes)
			)
		)
		(property "License" "Apache-2.0"
			(at 207.01 248.92 0)
			(effects
				(font
					(size 1.27 1.27)
					(thickness 0.15)
				)
				(justify left bottom)
				(hide yes)
			)
		)
		(pin "1"
		)
		(instances
			(project "data-center-rdimm-ddr5-tester"
				(path ""
					(reference "#PWR0107")
					(unit 1)
				)
			)
		)
	)
	(symbol
		(lib_id "antmicropower:GND")
		(at 40.64 242.57 0)
		(mirror y)
		(unit 1)
		(exclude_from_sim no)
		(in_bom yes)
		(on_board yes)
		(dnp no)
		(fields_autoplaced yes)
		(property "Reference" "#PWR076"
			(at 40.64 248.92 0)
			(effects
				(font
					(size 1.27 1.27)
				)
				(hide yes)
			)
		)
		(property "Value" "GND"
			(at 42.545 247.015 0)
			(effects
				(font
					(size 1.27 1.27)
					(thickness 0.15)
				)
				(justify left bottom)
			)
		)
		(property "Footprint" ""
			(at 31.75 250.19 0)
			(effects
				(font
					(size 1.27 1.27)
					(thickness 0.15)
				)
				(justify left bottom)
				(hide yes)
			)
		)
		(property "Datasheet" ""
			(at 31.75 255.27 0)
			(effects
				(font
					(size 1.27 1.27)
					(thickness 0.15)
				)
				(justify left bottom)
				(hide yes)
			)
		)
		(property "Description" ""
			(at 40.64 242.57 0)
			(effects
				(font
					(size 1.27 1.27)
				)
				(hide yes)
			)
		)
		(property "Author" "Antmicro"
			(at 31.75 247.65 0)
			(effects
				(font
					(size 1.27 1.27)
					(thickness 0.15)
				)
				(justify left bottom)
				(hide yes)
			)
		)
		(property "License" "Apache-2.0"
			(at 31.75 250.19 0)
			(effects
				(font
					(size 1.27 1.27)
					(thickness 0.15)
				)
				(justify left bottom)
				(hide yes)
			)
		)
		(pin "1"
		)
		(instances
			(project "data-center-rdimm-ddr5-tester"
				(path ""
					(reference "#PWR076")
					(unit 1)
				)
			)
		)
	)
	(symbol
		(lib_id "antmicropower:+1V2_MGTAVTT")
		(at 283.21 100.33 0)
		(unit 1)
		(exclude_from_sim no)
		(in_bom yes)
		(on_board yes)
		(dnp no)
		(fields_autoplaced yes)
		(property "Reference" "#PWR026"
			(at 283.21 104.14 0)
			(effects
				(font
					(size 1.27 1.27)
				)
				(hide yes)
			)
		)
		(property "Value" "+1V2_MGTAVTT"
			(at 283.21 95.885 0)
			(effects
				(font
					(size 1.27 1.27)
				)
			)
		)
		(property "Footprint" ""
			(at 283.21 100.33 0)
			(effects
				(font
					(size 1.27 1.27)
				)
				(hide yes)
			)
		)
		(property "Datasheet" ""
			(at 283.21 100.33 0)
			(effects
				(font
					(size 1.27 1.27)
				)
				(hide yes)
			)
		)
		(property "Description" ""
			(at 283.21 100.33 0)
			(effects
				(font
					(size 1.27 1.27)
				)
				(hide yes)
			)
		)
		(pin "1"
		)
		(instances
			(project "data-center-rdimm-ddr5-tester"
				(path ""
					(reference "#PWR026")
					(unit 1)
				)
			)
		)
	)
	(symbol
		(lib_id "antmicropower:GND")
		(at 339.09 66.04 0)
		(unit 1)
		(exclude_from_sim no)
		(in_bom yes)
		(on_board yes)
		(dnp no)
		(fields_autoplaced yes)
		(property "Reference" "#PWR0161"
			(at 339.09 72.39 0)
			(effects
				(font
					(size 1.27 1.27)
				)
				(hide yes)
			)
		)
		(property "Value" "GND"
			(at 337.185 70.485 0)
			(effects
				(font
					(size 1.27 1.27)
					(thickness 0.15)
				)
				(justify left bottom)
			)
		)
		(property "Footprint" ""
			(at 347.98 73.66 0)
			(effects
				(font
					(size 1.27 1.27)
					(thickness 0.15)
				)
				(justify left bottom)
				(hide yes)
			)
		)
		(property "Datasheet" ""
			(at 347.98 78.74 0)
			(effects
				(font
					(size 1.27 1.27)
					(thickness 0.15)
				)
				(justify left bottom)
				(hide yes)
			)
		)
		(property "Description" ""
			(at 339.09 66.04 0)
			(effects
				(font
					(size 1.27 1.27)
				)
				(hide yes)
			)
		)
		(property "Author" "Antmicro"
			(at 347.98 71.12 0)
			(effects
				(font
					(size 1.27 1.27)
					(thickness 0.15)
				)
				(justify left bottom)
				(hide yes)
			)
		)
		(property "License" "Apache-2.0"
			(at 347.98 73.66 0)
			(effects
				(font
					(size 1.27 1.27)
					(thickness 0.15)
				)
				(justify left bottom)
				(hide yes)
			)
		)
		(pin "1"
		)
		(instances
			(project "data-center-rdimm-ddr5-tester"
				(path ""
					(reference "#PWR0161")
					(unit 1)
				)
			)
		)
	)
	(symbol
		(lib_id "antmicropower:GND")
		(at 36.83 93.98 0)
		(mirror y)
		(unit 1)
		(exclude_from_sim no)
		(in_bom yes)
		(on_board yes)
		(dnp no)
		(fields_autoplaced yes)
		(property "Reference" "#PWR0110"
			(at 36.83 100.33 0)
			(effects
				(font
					(size 1.27 1.27)
				)
				(hide yes)
			)
		)
		(property "Value" "GND"
			(at 38.735 98.425 0)
			(effects
				(font
					(size 1.27 1.27)
					(thickness 0.15)
				)
				(justify left bottom)
			)
		)
		(property "Footprint" ""
			(at 27.94 101.6 0)
			(effects
				(font
					(size 1.27 1.27)
					(thickness 0.15)
				)
				(justify left bottom)
				(hide yes)
			)
		)
		(property "Datasheet" ""
			(at 27.94 106.68 0)
			(effects
				(font
					(size 1.27 1.27)
					(thickness 0.15)
				)
				(justify left bottom)
				(hide yes)
			)
		)
		(property "Description" ""
			(at 36.83 93.98 0)
			(effects
				(font
					(size 1.27 1.27)
				)
				(hide yes)
			)
		)
		(property "Author" "Antmicro"
			(at 27.94 99.06 0)
			(effects
				(font
					(size 1.27 1.27)
					(thickness 0.15)
				)
				(justify left bottom)
				(hide yes)
			)
		)
		(property "License" "Apache-2.0"
			(at 27.94 101.6 0)
			(effects
				(font
					(size 1.27 1.27)
					(thickness 0.15)
				)
				(justify left bottom)
				(hide yes)
			)
		)
		(pin "1"
		)
		(instances
			(project "data-center-rdimm-ddr5-tester"
				(path ""
					(reference "#PWR0110")
					(unit 1)
				)
			)
		)
	)
	(symbol
		(lib_id "antmicropower:VDD")
		(at 191.77 231.14 0)
		(unit 1)
		(exclude_from_sim no)
		(in_bom yes)
		(on_board yes)
		(dnp no)
		(fields_autoplaced yes)
		(property "Reference" "#PWR057"
			(at 191.77 234.95 0)
			(effects
				(font
					(size 1.27 1.27)
				)
				(hide yes)
			)
		)
		(property "Value" "VDDQ"
			(at 191.77 226.06 0)
			(effects
				(font
					(size 1.27 1.27)
				)
			)
		)
		(property "Footprint" ""
			(at 191.77 231.14 0)
			(effects
				(font
					(size 1.27 1.27)
				)
				(hide yes)
			)
		)
		(property "Datasheet" ""
			(at 191.77 231.14 0)
			(effects
				(font
					(size 1.27 1.27)
				)
				(hide yes)
			)
		)
		(property "Description" ""
			(at 191.77 231.14 0)
			(effects
				(font
					(size 1.27 1.27)
				)
				(hide yes)
			)
		)
		(pin "1"
		)
		(instances
			(project "data-center-rdimm-ddr5-tester"
				(path ""
					(reference "#PWR057")
					(unit 1)
				)
			)
		)
	)
	(symbol
		(lib_id "antmicroCapacitors0402:C_100n_0402")
		(at 53.34 119.38 90)
		(unit 1)
		(exclude_from_sim no)
		(in_bom yes)
		(on_board yes)
		(dnp no)
		(property "Reference" "C26"
			(at 53.975 114.935 90)
			(effects
				(font
					(size 1.27 1.27)
					(thickness 0.15)
				)
				(justify right)
			)
		)
		(property "Value" "C_100n_0402"
			(at 63.5 99.06 0)
			(effects
				(font
					(size 1.27 1.27)
					(thickness 0.15)
				)
				(justify left bottom)
				(hide yes)
			)
		)
		(property "Footprint" "antmicro-footprints:C_0402_1005Metric_EIA"
			(at 66.04 99.06 0)
			(effects
				(font
					(size 1.27 1.27)
					(thickness 0.15)
				)
				(justify left bottom)
				(hide yes)
			)
		)
		(property "Datasheet" "https://www.murata.com/products/productdetail?partno=GRM155R61H104KE14%23"
			(at 68.58 99.06 0)
			(effects
				(font
					(size 1.27 1.27)
					(thickness 0.15)
				)
				(justify left bottom)
				(hide yes)
			)
		)
		(property "Description" ""
			(at 53.34 119.38 0)
			(effects
				(font
					(size 1.27 1.27)
				)
				(hide yes)
			)
		)
		(property "MPN" "GRM155R61H104KE14D"
			(at 71.12 99.06 0)
			(effects
				(font
					(size 1.27 1.27)
					(thickness 0.15)
				)
				(justify left bottom)
				(hide yes)
			)
		)
		(property "Manufacturer" "Murata"
			(at 73.66 99.06 0)
			(effects
				(font
					(size 1.27 1.27)
					(thickness 0.15)
				)
				(justify left bottom)
				(hide yes)
			)
		)
		(property "License" "Apache-2.0"
			(at 76.2 99.06 0)
			(effects
				(font
					(size 1.27 1.27)
					(thickness 0.15)
				)
				(justify left bottom)
				(hide yes)
			)
		)
		(property "Author" "Antmicro"
			(at 78.74 99.06 0)
			(effects
				(font
					(size 1.27 1.27)
					(thickness 0.15)
				)
				(justify left bottom)
				(hide yes)
			)
		)
		(property "Val" "100n"
			(at 53.975 118.745 90)
			(effects
				(font
					(size 1.27 1.27)
					(thickness 0.15)
				)
				(justify right)
			)
		)
		(property "Voltage" "50V"
			(at 81.28 99.06 0)
			(effects
				(font
					(size 1.27 1.27)
				)
				(justify left bottom)
				(hide yes)
			)
		)
		(property "Dielectric" "X5R"
			(at 83.82 99.06 0)
			(effects
				(font
					(size 1.27 1.27)
				)
				(justify left bottom)
				(hide yes)
			)
		)
		(pin "1"
		)
		(pin "2"
		)
		(instances
			(project "data-center-rdimm-ddr5-tester"
				(path ""
					(reference "C26")
					(unit 1)
				)
			)
		)
	)
	(symbol
		(lib_id "antmicropower:GND")
		(at 71.12 67.31 0)
		(mirror y)
		(unit 1)
		(exclude_from_sim no)
		(in_bom yes)
		(on_board yes)
		(dnp no)
		(fields_autoplaced yes)
		(property "Reference" "#PWR085"
			(at 71.12 73.66 0)
			(effects
				(font
					(size 1.27 1.27)
				)
				(hide yes)
			)
		)
		(property "Value" "GND"
			(at 73.025 71.755 0)
			(effects
				(font
					(size 1.27 1.27)
					(thickness 0.15)
				)
				(justify left bottom)
			)
		)
		(property "Footprint" ""
			(at 62.23 74.93 0)
			(effects
				(font
					(size 1.27 1.27)
					(thickness 0.15)
				)
				(justify left bottom)
				(hide yes)
			)
		)
		(property "Datasheet" ""
			(at 62.23 80.01 0)
			(effects
				(font
					(size 1.27 1.27)
					(thickness 0.15)
				)
				(justify left bottom)
				(hide yes)
			)
		)
		(property "Description" ""
			(at 71.12 67.31 0)
			(effects
				(font
					(size 1.27 1.27)
				)
				(hide yes)
			)
		)
		(property "Author" "Antmicro"
			(at 62.23 72.39 0)
			(effects
				(font
					(size 1.27 1.27)
					(thickness 0.15)
				)
				(justify left bottom)
				(hide yes)
			)
		)
		(property "License" "Apache-2.0"
			(at 62.23 74.93 0)
			(effects
				(font
					(size 1.27 1.27)
					(thickness 0.15)
				)
				(justify left bottom)
				(hide yes)
			)
		)
		(pin "1"
		)
		(instances
			(project "data-center-rdimm-ddr5-tester"
				(path ""
					(reference "#PWR085")
					(unit 1)
				)
			)
		)
	)
	(symbol
		(lib_id "antmicropower:GND")
		(at 86.36 148.59 0)
		(unit 1)
		(exclude_from_sim no)
		(in_bom yes)
		(on_board yes)
		(dnp no)
		(fields_autoplaced yes)
		(property "Reference" "#PWR090"
			(at 86.36 154.94 0)
			(effects
				(font
					(size 1.27 1.27)
				)
				(hide yes)
			)
		)
		(property "Value" "GND"
			(at 84.455 153.035 0)
			(effects
				(font
					(size 1.27 1.27)
					(thickness 0.15)
				)
				(justify left bottom)
			)
		)
		(property "Footprint" ""
			(at 95.25 156.21 0)
			(effects
				(font
					(size 1.27 1.27)
					(thickness 0.15)
				)
				(justify left bottom)
				(hide yes)
			)
		)
		(property "Datasheet" ""
			(at 95.25 161.29 0)
			(effects
				(font
					(size 1.27 1.27)
					(thickness 0.15)
				)
				(justify left bottom)
				(hide yes)
			)
		)
		(property "Description" ""
			(at 86.36 148.59 0)
			(effects
				(font
					(size 1.27 1.27)
				)
				(hide yes)
			)
		)
		(property "Author" "Antmicro"
			(at 95.25 153.67 0)
			(effects
				(font
					(size 1.27 1.27)
					(thickness 0.15)
				)
				(justify left bottom)
				(hide yes)
			)
		)
		(property "License" "Apache-2.0"
			(at 95.25 156.21 0)
			(effects
				(font
					(size 1.27 1.27)
					(thickness 0.15)
				)
				(justify left bottom)
				(hide yes)
			)
		)
		(pin "1"
		)
		(instances
			(project "data-center-rdimm-ddr5-tester"
				(path ""
					(reference "#PWR090")
					(unit 1)
				)
			)
		)
	)
	(symbol
		(lib_id "antmicropower:GND")
		(at 44.45 148.59 0)
		(unit 1)
		(exclude_from_sim no)
		(in_bom yes)
		(on_board yes)
		(dnp no)
		(fields_autoplaced yes)
		(property "Reference" "#PWR082"
			(at 44.45 154.94 0)
			(effects
				(font
					(size 1.27 1.27)
				)
				(hide yes)
			)
		)
		(property "Value" "GND"
			(at 42.545 153.035 0)
			(effects
				(font
					(size 1.27 1.27)
					(thickness 0.15)
				)
				(justify left bottom)
			)
		)
		(property "Footprint" ""
			(at 53.34 156.21 0)
			(effects
				(font
					(size 1.27 1.27)
					(thickness 0.15)
				)
				(justify left bottom)
				(hide yes)
			)
		)
		(property "Datasheet" ""
			(at 53.34 161.29 0)
			(effects
				(font
					(size 1.27 1.27)
					(thickness 0.15)
				)
				(justify left bottom)
				(hide yes)
			)
		)
		(property "Description" ""
			(at 44.45 148.59 0)
			(effects
				(font
					(size 1.27 1.27)
				)
				(hide yes)
			)
		)
		(property "Author" "Antmicro"
			(at 53.34 153.67 0)
			(effects
				(font
					(size 1.27 1.27)
					(thickness 0.15)
				)
				(justify left bottom)
				(hide yes)
			)
		)
		(property "License" "Apache-2.0"
			(at 53.34 156.21 0)
			(effects
				(font
					(size 1.27 1.27)
					(thickness 0.15)
				)
				(justify left bottom)
				(hide yes)
			)
		)
		(pin "1"
		)
		(instances
			(project "data-center-rdimm-ddr5-tester"
				(path ""
					(reference "#PWR082")
					(unit 1)
				)
			)
		)
	)
	(symbol
		(lib_id "antmicropower:GND")
		(at 69.85 173.99 0)
		(unit 1)
		(exclude_from_sim no)
		(in_bom yes)
		(on_board yes)
		(dnp no)
		(fields_autoplaced yes)
		(property "Reference" "#PWR0103"
			(at 69.85 180.34 0)
			(effects
				(font
					(size 1.27 1.27)
				)
				(hide yes)
			)
		)
		(property "Value" "GND"
			(at 67.945 178.435 0)
			(effects
				(font
					(size 1.27 1.27)
					(thickness 0.15)
				)
				(justify left bottom)
			)
		)
		(property "Footprint" ""
			(at 78.74 181.61 0)
			(effects
				(font
					(size 1.27 1.27)
					(thickness 0.15)
				)
				(justify left bottom)
				(hide yes)
			)
		)
		(property "Datasheet" ""
			(at 78.74 186.69 0)
			(effects
				(font
					(size 1.27 1.27)
					(thickness 0.15)
				)
				(justify left bottom)
				(hide yes)
			)
		)
		(property "Description" ""
			(at 69.85 173.99 0)
			(effects
				(font
					(size 1.27 1.27)
				)
				(hide yes)
			)
		)
		(property "Author" "Antmicro"
			(at 78.74 179.07 0)
			(effects
				(font
					(size 1.27 1.27)
					(thickness 0.15)
				)
				(justify left bottom)
				(hide yes)
			)
		)
		(property "License" "Apache-2.0"
			(at 78.74 181.61 0)
			(effects
				(font
					(size 1.27 1.27)
					(thickness 0.15)
				)
				(justify left bottom)
				(hide yes)
			)
		)
		(pin "1"
		)
		(instances
			(project "data-center-rdimm-ddr5-tester"
				(path ""
					(reference "#PWR0103")
					(unit 1)
				)
			)
		)
	)
	(symbol
		(lib_id "antmicroCapacitors0603:C_47u_0603")
		(at 322.58 59.69 270)
		(unit 1)
		(exclude_from_sim no)
		(in_bom yes)
		(on_board yes)
		(dnp no)
		(property "Reference" "C14"
			(at 322.58 60.325 90)
			(effects
				(font
					(size 1.27 1.27)
				)
				(justify left)
			)
		)
		(property "Value" "C_47u_0603"
			(at 312.42 80.01 0)
			(effects
				(font
					(size 1.27 1.27)
					(thickness 0.15)
				)
				(justify left bottom)
				(hide yes)
			)
		)
		(property "Footprint" "antmicro-footprints:C_0603_1608Metric"
			(at 309.88 80.01 0)
			(effects
				(font
					(size 1.27 1.27)
					(thickness 0.15)
				)
				(justify left bottom)
				(hide yes)
			)
		)
		(property "Datasheet" "https://www.murata.com/products/productdetail?partno=GRM188R60J476ME15%23"
			(at 307.34 80.01 0)
			(effects
				(font
					(size 1.27 1.27)
					(thickness 0.15)
				)
				(justify left bottom)
				(hide yes)
			)
		)
		(property "Description" ""
			(at 322.58 59.69 0)
			(effects
				(font
					(size 1.27 1.27)
				)
				(hide yes)
			)
		)
		(property "Manufacturer" "Murata"
			(at 302.26 80.01 0)
			(effects
				(font
					(size 1.27 1.27)
					(thickness 0.15)
				)
				(justify left bottom)
				(hide yes)
			)
		)
		(property "MPN" "GRM188R60J476ME15D"
			(at 304.8 80.01 0)
			(effects
				(font
					(size 1.27 1.27)
					(thickness 0.15)
				)
				(justify left bottom)
				(hide yes)
			)
		)
		(property "Val" "47u"
			(at 322.58 64.135 90)
			(effects
				(font
					(size 1.27 1.27)
					(thickness 0.15)
				)
				(justify left)
			)
		)
		(property "License" "Apache-2.0"
			(at 299.72 80.01 0)
			(effects
				(font
					(size 1.27 1.27)
					(thickness 0.15)
				)
				(justify left bottom)
				(hide yes)
			)
		)
		(property "Author" "Antmicro"
			(at 297.18 80.01 0)
			(effects
				(font
					(size 1.27 1.27)
					(thickness 0.15)
				)
				(justify left bottom)
				(hide yes)
			)
		)
		(property "Voltage" ""
			(at 294.64 80.01 0)
			(effects
				(font
					(size 1.27 1.27)
				)
				(justify left bottom)
				(hide yes)
			)
		)
		(property "Dielectric" ""
			(at 292.1 80.01 0)
			(effects
				(font
					(size 1.27 1.27)
				)
				(justify left bottom)
				(hide yes)
			)
		)
		(pin "1"
		)
		(pin "2"
		)
		(instances
			(project "data-center-rdimm-ddr5-tester"
				(path ""
					(reference "C14")
					(unit 1)
				)
			)
		)
	)
	(symbol
		(lib_id "antmicropower:GND")
		(at 38.1 67.31 0)
		(mirror y)
		(unit 1)
		(exclude_from_sim no)
		(in_bom yes)
		(on_board yes)
		(dnp no)
		(fields_autoplaced yes)
		(property "Reference" "#PWR054"
			(at 38.1 73.66 0)
			(effects
				(font
					(size 1.27 1.27)
				)
				(hide yes)
			)
		)
		(property "Value" "GND"
			(at 40.005 71.755 0)
			(effects
				(font
					(size 1.27 1.27)
					(thickness 0.15)
				)
				(justify left bottom)
			)
		)
		(property "Footprint" ""
			(at 29.21 74.93 0)
			(effects
				(font
					(size 1.27 1.27)
					(thickness 0.15)
				)
				(justify left bottom)
				(hide yes)
			)
		)
		(property "Datasheet" ""
			(at 29.21 80.01 0)
			(effects
				(font
					(size 1.27 1.27)
					(thickness 0.15)
				)
				(justify left bottom)
				(hide yes)
			)
		)
		(property "Description" ""
			(at 38.1 67.31 0)
			(effects
				(font
					(size 1.27 1.27)
				)
				(hide yes)
			)
		)
		(property "Author" "Antmicro"
			(at 29.21 72.39 0)
			(effects
				(font
					(size 1.27 1.27)
					(thickness 0.15)
				)
				(justify left bottom)
				(hide yes)
			)
		)
		(property "License" "Apache-2.0"
			(at 29.21 74.93 0)
			(effects
				(font
					(size 1.27 1.27)
					(thickness 0.15)
				)
				(justify left bottom)
				(hide yes)
			)
		)
		(pin "1"
		)
		(instances
			(project "data-center-rdimm-ddr5-tester"
				(path ""
					(reference "#PWR054")
					(unit 1)
				)
			)
		)
	)
	(symbol
		(lib_id "antmicroCapacitors0402:C_1u_25V_0402")
		(at 104.14 196.85 90)
		(unit 1)
		(exclude_from_sim no)
		(in_bom yes)
		(on_board yes)
		(dnp no)
		(fields_autoplaced yes)
		(property "Reference" "C247"
			(at 106.68 193.0336 90)
			(effects
				(font
					(size 1.27 1.27)
					(thickness 0.15)
				)
				(justify right)
			)
		)
		(property "Value" "C_1u_25V_0402"
			(at 114.3 176.53 0)
			(effects
				(font
					(size 1.27 1.27)
					(thickness 0.15)
				)
				(justify left bottom)
				(hide yes)
			)
		)
		(property "Footprint" "antmicro-footprints:C_0402_1005Metric_EIA"
			(at 116.84 176.53 0)
			(effects
				(font
					(size 1.27 1.27)
					(thickness 0.15)
				)
				(justify left bottom)
				(hide yes)
			)
		)
		(property "Datasheet" "https://www.murata.com/products/productdetail?partno=GRM155R61E105KE11%23"
			(at 119.38 176.53 0)
			(effects
				(font
					(size 1.27 1.27)
					(thickness 0.15)
				)
				(justify left bottom)
				(hide yes)
			)
		)
		(property "Description" ""
			(at 104.14 196.85 0)
			(effects
				(font
					(size 1.27 1.27)
				)
				(hide yes)
			)
		)
		(property "MPN" "GRM155R61E105KE11J"
			(at 121.92 176.53 0)
			(effects
				(font
					(size 1.27 1.27)
					(thickness 0.15)
				)
				(justify left bottom)
				(hide yes)
			)
		)
		(property "Manufacturer" "Murata"
			(at 124.46 176.53 0)
			(effects
				(font
					(size 1.27 1.27)
					(thickness 0.15)
				)
				(justify left bottom)
				(hide yes)
			)
		)
		(property "License" "Apache-2.0"
			(at 127 176.53 0)
			(effects
				(font
					(size 1.27 1.27)
					(thickness 0.15)
				)
				(justify left bottom)
				(hide yes)
			)
		)
		(property "Author" "Antmicro"
			(at 129.54 176.53 0)
			(effects
				(font
					(size 1.27 1.27)
					(thickness 0.15)
				)
				(justify left bottom)
				(hide yes)
			)
		)
		(property "Val" "1u"
			(at 106.68 195.5736 90)
			(effects
				(font
					(size 1.27 1.27)
					(thickness 0.15)
				)
				(justify right)
			)
		)
		(property "Voltage" "25V"
			(at 132.08 176.53 0)
			(effects
				(font
					(size 1.27 1.27)
				)
				(justify left bottom)
				(hide yes)
			)
		)
		(property "Dielectric" "X5R"
			(at 134.62 176.53 0)
			(effects
				(font
					(size 1.27 1.27)
				)
				(justify left bottom)
				(hide yes)
			)
		)
		(pin "1"
		)
		(pin "2"
		)
		(instances
			(project "data-center-rdimm-ddr5-tester"
				(path ""
					(reference "C247")
					(unit 1)
				)
			)
		)
	)
	(symbol
		(lib_id "antmicroCapacitors0402:C_1u_25V_0402")
		(at 87.63 196.85 90)
		(unit 1)
		(exclude_from_sim no)
		(in_bom yes)
		(on_board yes)
		(dnp no)
		(fields_autoplaced yes)
		(property "Reference" "C92"
			(at 90.17 193.0336 90)
			(effects
				(font
					(size 1.27 1.27)
					(thickness 0.15)
				)
				(justify right)
			)
		)
		(property "Value" "C_1u_25V_0402"
			(at 97.79 176.53 0)
			(effects
				(font
					(size 1.27 1.27)
					(thickness 0.15)
				)
				(justify left bottom)
				(hide yes)
			)
		)
		(property "Footprint" "antmicro-footprints:C_0402_1005Metric_EIA"
			(at 100.33 176.53 0)
			(effects
				(font
					(size 1.27 1.27)
					(thickness 0.15)
				)
				(justify left bottom)
				(hide yes)
			)
		)
		(property "Datasheet" "https://www.murata.com/products/productdetail?partno=GRM155R61E105KE11%23"
			(at 102.87 176.53 0)
			(effects
				(font
					(size 1.27 1.27)
					(thickness 0.15)
				)
				(justify left bottom)
				(hide yes)
			)
		)
		(property "Description" ""
			(at 87.63 196.85 0)
			(effects
				(font
					(size 1.27 1.27)
				)
				(hide yes)
			)
		)
		(property "MPN" "GRM155R61E105KE11J"
			(at 105.41 176.53 0)
			(effects
				(font
					(size 1.27 1.27)
					(thickness 0.15)
				)
				(justify left bottom)
				(hide yes)
			)
		)
		(property "Manufacturer" "Murata"
			(at 107.95 176.53 0)
			(effects
				(font
					(size 1.27 1.27)
					(thickness 0.15)
				)
				(justify left bottom)
				(hide yes)
			)
		)
		(property "License" "Apache-2.0"
			(at 110.49 176.53 0)
			(effects
				(font
					(size 1.27 1.27)
					(thickness 0.15)
				)
				(justify left bottom)
				(hide yes)
			)
		)
		(property "Author" "Antmicro"
			(at 113.03 176.53 0)
			(effects
				(font
					(size 1.27 1.27)
					(thickness 0.15)
				)
				(justify left bottom)
				(hide yes)
			)
		)
		(property "Val" "1u"
			(at 90.17 195.5736 90)
			(effects
				(font
					(size 1.27 1.27)
					(thickness 0.15)
				)
				(justify right)
			)
		)
		(property "Voltage" "25V"
			(at 115.57 176.53 0)
			(effects
				(font
					(size 1.27 1.27)
				)
				(justify left bottom)
				(hide yes)
			)
		)
		(property "Dielectric" "X5R"
			(at 118.11 176.53 0)
			(effects
				(font
					(size 1.27 1.27)
				)
				(justify left bottom)
				(hide yes)
			)
		)
		(pin "1"
		)
		(pin "2"
		)
		(instances
			(project "data-center-rdimm-ddr5-tester"
				(path ""
					(reference "C92")
					(unit 1)
				)
			)
		)
	)
	(symbol
		(lib_id "antmicropower:GND")
		(at 325.12 101.6 0)
		(unit 1)
		(exclude_from_sim no)
		(in_bom yes)
		(on_board yes)
		(dnp no)
		(fields_autoplaced yes)
		(property "Reference" "#PWR0116"
			(at 325.12 107.95 0)
			(effects
				(font
					(size 1.27 1.27)
				)
				(hide yes)
			)
		)
		(property "Value" "GND"
			(at 323.215 106.045 0)
			(effects
				(font
					(size 1.27 1.27)
					(thickness 0.15)
				)
				(justify left bottom)
			)
		)
		(property "Footprint" ""
			(at 334.01 109.22 0)
			(effects
				(font
					(size 1.27 1.27)
					(thickness 0.15)
				)
				(justify left bottom)
				(hide yes)
			)
		)
		(property "Datasheet" ""
			(at 334.01 114.3 0)
			(effects
				(font
					(size 1.27 1.27)
					(thickness 0.15)
				)
				(justify left bottom)
				(hide yes)
			)
		)
		(property "Description" ""
			(at 325.12 101.6 0)
			(effects
				(font
					(size 1.27 1.27)
				)
				(hide yes)
			)
		)
		(property "Author" "Antmicro"
			(at 334.01 106.68 0)
			(effects
				(font
					(size 1.27 1.27)
					(thickness 0.15)
				)
				(justify left bottom)
				(hide yes)
			)
		)
		(property "License" "Apache-2.0"
			(at 334.01 109.22 0)
			(effects
				(font
					(size 1.27 1.27)
					(thickness 0.15)
				)
				(justify left bottom)
				(hide yes)
			)
		)
		(pin "1"
		)
		(instances
			(project "data-center-rdimm-ddr5-tester"
				(path ""
					(reference "#PWR0116")
					(unit 1)
				)
			)
		)
	)
	(symbol
		(lib_id "antmicroCapacitors0402:C_1u_25V_0402")
		(at 62.23 196.85 90)
		(unit 1)
		(exclude_from_sim no)
		(in_bom yes)
		(on_board yes)
		(dnp no)
		(fields_autoplaced yes)
		(property "Reference" "C86"
			(at 64.77 193.0336 90)
			(effects
				(font
					(size 1.27 1.27)
					(thickness 0.15)
				)
				(justify right)
			)
		)
		(property "Value" "C_1u_25V_0402"
			(at 72.39 176.53 0)
			(effects
				(font
					(size 1.27 1.27)
					(thickness 0.15)
				)
				(justify left bottom)
				(hide yes)
			)
		)
		(property "Footprint" "antmicro-footprints:C_0402_1005Metric_EIA"
			(at 74.93 176.53 0)
			(effects
				(font
					(size 1.27 1.27)
					(thickness 0.15)
				)
				(justify left bottom)
				(hide yes)
			)
		)
		(property "Datasheet" "https://www.murata.com/products/productdetail?partno=GRM155R61E105KE11%23"
			(at 77.47 176.53 0)
			(effects
				(font
					(size 1.27 1.27)
					(thickness 0.15)
				)
				(justify left bottom)
				(hide yes)
			)
		)
		(property "Description" ""
			(at 62.23 196.85 0)
			(effects
				(font
					(size 1.27 1.27)
				)
				(hide yes)
			)
		)
		(property "MPN" "GRM155R61E105KE11J"
			(at 80.01 176.53 0)
			(effects
				(font
					(size 1.27 1.27)
					(thickness 0.15)
				)
				(justify left bottom)
				(hide yes)
			)
		)
		(property "Manufacturer" "Murata"
			(at 82.55 176.53 0)
			(effects
				(font
					(size 1.27 1.27)
					(thickness 0.15)
				)
				(justify left bottom)
				(hide yes)
			)
		)
		(property "License" "Apache-2.0"
			(at 85.09 176.53 0)
			(effects
				(font
					(size 1.27 1.27)
					(thickness 0.15)
				)
				(justify left bottom)
				(hide yes)
			)
		)
		(property "Author" "Antmicro"
			(at 87.63 176.53 0)
			(effects
				(font
					(size 1.27 1.27)
					(thickness 0.15)
				)
				(justify left bottom)
				(hide yes)
			)
		)
		(property "Val" "1u"
			(at 64.77 195.5736 90)
			(effects
				(font
					(size 1.27 1.27)
					(thickness 0.15)
				)
				(justify right)
			)
		)
		(property "Voltage" "25V"
			(at 90.17 176.53 0)
			(effects
				(font
					(size 1.27 1.27)
				)
				(justify left bottom)
				(hide yes)
			)
		)
		(property "Dielectric" "X5R"
			(at 92.71 176.53 0)
			(effects
				(font
					(size 1.27 1.27)
				)
				(justify left bottom)
				(hide yes)
			)
		)
		(pin "1"
		)
		(pin "2"
		)
		(instances
			(project "data-center-rdimm-ddr5-tester"
				(path ""
					(reference "C86")
					(unit 1)
				)
			)
		)
	)
	(symbol
		(lib_id "antmicroCapacitors0603:C_47u_0603")
		(at 191.77 234.95 270)
		(unit 1)
		(exclude_from_sim no)
		(in_bom yes)
		(on_board yes)
		(dnp no)
		(property "Reference" "C44"
			(at 191.77 235.585 90)
			(effects
				(font
					(size 1.27 1.27)
				)
				(justify left)
			)
		)
		(property "Value" "C_47u_0603"
			(at 181.61 255.27 0)
			(effects
				(font
					(size 1.27 1.27)
					(thickness 0.15)
				)
				(justify left bottom)
				(hide yes)
			)
		)
		(property "Footprint" "antmicro-footprints:C_0603_1608Metric"
			(at 179.07 255.27 0)
			(effects
				(font
					(size 1.27 1.27)
					(thickness 0.15)
				)
				(justify left bottom)
				(hide yes)
			)
		)
		(property "Datasheet" "https://www.murata.com/products/productdetail?partno=GRM188R60J476ME15%23"
			(at 176.53 255.27 0)
			(effects
				(font
					(size 1.27 1.27)
					(thickness 0.15)
				)
				(justify left bottom)
				(hide yes)
			)
		)
		(property "Description" ""
			(at 191.77 234.95 0)
			(effects
				(font
					(size 1.27 1.27)
				)
				(hide yes)
			)
		)
		(property "Manufacturer" "Murata"
			(at 171.45 255.27 0)
			(effects
				(font
					(size 1.27 1.27)
					(thickness 0.15)
				)
				(justify left bottom)
				(hide yes)
			)
		)
		(property "MPN" "GRM188R60J476ME15D"
			(at 173.99 255.27 0)
			(effects
				(font
					(size 1.27 1.27)
					(thickness 0.15)
				)
				(justify left bottom)
				(hide yes)
			)
		)
		(property "Val" "47u"
			(at 191.77 239.395 90)
			(effects
				(font
					(size 1.27 1.27)
					(thickness 0.15)
				)
				(justify left)
			)
		)
		(property "License" "Apache-2.0"
			(at 168.91 255.27 0)
			(effects
				(font
					(size 1.27 1.27)
					(thickness 0.15)
				)
				(justify left bottom)
				(hide yes)
			)
		)
		(property "Author" "Antmicro"
			(at 166.37 255.27 0)
			(effects
				(font
					(size 1.27 1.27)
					(thickness 0.15)
				)
				(justify left bottom)
				(hide yes)
			)
		)
		(property "Voltage" ""
			(at 163.83 255.27 0)
			(effects
				(font
					(size 1.27 1.27)
				)
				(justify left bottom)
				(hide yes)
			)
		)
		(property "Dielectric" ""
			(at 161.29 255.27 0)
			(effects
				(font
					(size 1.27 1.27)
				)
				(justify left bottom)
				(hide yes)
			)
		)
		(pin "1"
		)
		(pin "2"
		)
		(instances
			(project "data-center-rdimm-ddr5-tester"
				(path ""
					(reference "C44")
					(unit 1)
				)
			)
		)
	)
	(symbol
		(lib_id "antmicropower:GND")
		(at 78.74 120.65 0)
		(unit 1)
		(exclude_from_sim no)
		(in_bom yes)
		(on_board yes)
		(dnp no)
		(fields_autoplaced yes)
		(property "Reference" "#PWR095"
			(at 78.74 127 0)
			(effects
				(font
					(size 1.27 1.27)
				)
				(hide yes)
			)
		)
		(property "Value" "GND"
			(at 76.835 125.095 0)
			(effects
				(font
					(size 1.27 1.27)
					(thickness 0.15)
				)
				(justify left bottom)
			)
		)
		(property "Footprint" ""
			(at 87.63 128.27 0)
			(effects
				(font
					(size 1.27 1.27)
					(thickness 0.15)
				)
				(justify left bottom)
				(hide yes)
			)
		)
		(property "Datasheet" ""
			(at 87.63 133.35 0)
			(effects
				(font
					(size 1.27 1.27)
					(thickness 0.15)
				)
				(justify left bottom)
				(hide yes)
			)
		)
		(property "Description" ""
			(at 78.74 120.65 0)
			(effects
				(font
					(size 1.27 1.27)
				)
				(hide yes)
			)
		)
		(property "Author" "Antmicro"
			(at 87.63 125.73 0)
			(effects
				(font
					(size 1.27 1.27)
					(thickness 0.15)
				)
				(justify left bottom)
				(hide yes)
			)
		)
		(property "License" "Apache-2.0"
			(at 87.63 128.27 0)
			(effects
				(font
					(size 1.27 1.27)
					(thickness 0.15)
				)
				(justify left bottom)
				(hide yes)
			)
		)
		(pin "1"
		)
		(instances
			(project "data-center-rdimm-ddr5-tester"
				(path ""
					(reference "#PWR095")
					(unit 1)
				)
			)
		)
	)
	(symbol
		(lib_id "antmicroCapacitors0402:C_1u_25V_0402")
		(at 60.96 147.32 90)
		(unit 1)
		(exclude_from_sim no)
		(in_bom yes)
		(on_board yes)
		(dnp no)
		(fields_autoplaced yes)
		(property "Reference" "C39"
			(at 63.5 143.5036 90)
			(effects
				(font
					(size 1.27 1.27)
					(thickness 0.15)
				)
				(justify right)
			)
		)
		(property "Value" "C_1u_25V_0402"
			(at 71.12 127 0)
			(effects
				(font
					(size 1.27 1.27)
					(thickness 0.15)
				)
				(justify left bottom)
				(hide yes)
			)
		)
		(property "Footprint" "antmicro-footprints:C_0402_1005Metric_EIA"
			(at 73.66 127 0)
			(effects
				(font
					(size 1.27 1.27)
					(thickness 0.15)
				)
				(justify left bottom)
				(hide yes)
			)
		)
		(property "Datasheet" "https://www.murata.com/products/productdetail?partno=GRM155R61E105KE11%23"
			(at 76.2 127 0)
			(effects
				(font
					(size 1.27 1.27)
					(thickness 0.15)
				)
				(justify left bottom)
				(hide yes)
			)
		)
		(property "Description" ""
			(at 60.96 147.32 0)
			(effects
				(font
					(size 1.27 1.27)
				)
				(hide yes)
			)
		)
		(property "MPN" "GRM155R61E105KE11J"
			(at 78.74 127 0)
			(effects
				(font
					(size 1.27 1.27)
					(thickness 0.15)
				)
				(justify left bottom)
				(hide yes)
			)
		)
		(property "Manufacturer" "Murata"
			(at 81.28 127 0)
			(effects
				(font
					(size 1.27 1.27)
					(thickness 0.15)
				)
				(justify left bottom)
				(hide yes)
			)
		)
		(property "License" "Apache-2.0"
			(at 83.82 127 0)
			(effects
				(font
					(size 1.27 1.27)
					(thickness 0.15)
				)
				(justify left bottom)
				(hide yes)
			)
		)
		(property "Author" "Antmicro"
			(at 86.36 127 0)
			(effects
				(font
					(size 1.27 1.27)
					(thickness 0.15)
				)
				(justify left bottom)
				(hide yes)
			)
		)
		(property "Val" "1u"
			(at 63.5 146.0436 90)
			(effects
				(font
					(size 1.27 1.27)
					(thickness 0.15)
				)
				(justify right)
			)
		)
		(property "Voltage" "25V"
			(at 88.9 127 0)
			(effects
				(font
					(size 1.27 1.27)
				)
				(justify left bottom)
				(hide yes)
			)
		)
		(property "Dielectric" "X5R"
			(at 91.44 127 0)
			(effects
				(font
					(size 1.27 1.27)
				)
				(justify left bottom)
				(hide yes)
			)
		)
		(pin "1"
		)
		(pin "2"
		)
		(instances
			(project "data-center-rdimm-ddr5-tester"
				(path ""
					(reference "C39")
					(unit 1)
				)
			)
		)
	)
	(symbol
		(lib_id "antmicropower:GND")
		(at 34.29 242.57 0)
		(mirror y)
		(unit 1)
		(exclude_from_sim no)
		(in_bom yes)
		(on_board yes)
		(dnp no)
		(fields_autoplaced yes)
		(property "Reference" "#PWR074"
			(at 34.29 248.92 0)
			(effects
				(font
					(size 1.27 1.27)
				)
				(hide yes)
			)
		)
		(property "Value" "GND"
			(at 36.195 247.015 0)
			(effects
				(font
					(size 1.27 1.27)
					(thickness 0.15)
				)
				(justify left bottom)
			)
		)
		(property "Footprint" ""
			(at 25.4 250.19 0)
			(effects
				(font
					(size 1.27 1.27)
					(thickness 0.15)
				)
				(justify left bottom)
				(hide yes)
			)
		)
		(property "Datasheet" ""
			(at 25.4 255.27 0)
			(effects
				(font
					(size 1.27 1.27)
					(thickness 0.15)
				)
				(justify left bottom)
				(hide yes)
			)
		)
		(property "Description" ""
			(at 34.29 242.57 0)
			(effects
				(font
					(size 1.27 1.27)
				)
				(hide yes)
			)
		)
		(property "Author" "Antmicro"
			(at 25.4 247.65 0)
			(effects
				(font
					(size 1.27 1.27)
					(thickness 0.15)
				)
				(justify left bottom)
				(hide yes)
			)
		)
		(property "License" "Apache-2.0"
			(at 25.4 250.19 0)
			(effects
				(font
					(size 1.27 1.27)
					(thickness 0.15)
				)
				(justify left bottom)
				(hide yes)
			)
		)
		(pin "1"
		)
		(instances
			(project "data-center-rdimm-ddr5-tester"
				(path ""
					(reference "#PWR074")
					(unit 1)
				)
			)
		)
	)
	(symbol
		(lib_id "antmicropower:GND")
		(at 173.99 271.78 0)
		(unit 1)
		(exclude_from_sim no)
		(in_bom yes)
		(on_board yes)
		(dnp no)
		(fields_autoplaced yes)
		(property "Reference" "#PWR0125"
			(at 173.99 278.13 0)
			(effects
				(font
					(size 1.27 1.27)
				)
				(hide yes)
			)
		)
		(property "Value" "GND"
			(at 172.085 276.225 0)
			(effects
				(font
					(size 1.27 1.27)
					(thickness 0.15)
				)
				(justify left bottom)
			)
		)
		(property "Footprint" ""
			(at 182.88 279.4 0)
			(effects
				(font
					(size 1.27 1.27)
					(thickness 0.15)
				)
				(justify left bottom)
				(hide yes)
			)
		)
		(property "Datasheet" ""
			(at 182.88 284.48 0)
			(effects
				(font
					(size 1.27 1.27)
					(thickness 0.15)
				)
				(justify left bottom)
				(hide yes)
			)
		)
		(property "Description" ""
			(at 173.99 271.78 0)
			(effects
				(font
					(size 1.27 1.27)
				)
				(hide yes)
			)
		)
		(property "Author" "Antmicro"
			(at 182.88 276.86 0)
			(effects
				(font
					(size 1.27 1.27)
					(thickness 0.15)
				)
				(justify left bottom)
				(hide yes)
			)
		)
		(property "License" "Apache-2.0"
			(at 182.88 279.4 0)
			(effects
				(font
					(size 1.27 1.27)
					(thickness 0.15)
				)
				(justify left bottom)
				(hide yes)
			)
		)
		(pin "1"
		)
		(instances
			(project "data-center-rdimm-ddr5-tester"
				(path ""
					(reference "#PWR0125")
					(unit 1)
				)
			)
		)
	)
)
